(kicad_sch
	(version 20250114)
	(generator "eeschema")
	(generator_version "9.0")
	(paper "A3")
	(title_block
		(title "Kintex 410T devboard")
		(date "2024-04-03")
		(rev "1.1.2")
	)
	(text "JTAG Connector"
		(exclude_from_sim no)
		(at 45.085 205.105 0)
		(effects
			(font
				(size 1.27 1.27)
				(thickness 0.4)
				(bold yes)
			)
			(justify left bottom)
		)
	)
	(text "Todo:\n-Connect I2C"
		(exclude_from_sim no)
		(at 1.27 5.08 0)
		(effects
			(font
				(size 1.27 1.27)
				(bold yes)
			)
			(justify left bottom)
		)
	)
	(text "Config. mode\nMaster Serial\nMaster SPI\nMaster BPI\nMaster SelectMAP\nJTAG\nSlave SelectMAP\nSlave Serial"
		(exclude_from_sim no)
		(at 99.06 111.125 0)
		(effects
			(font
				(size 1.27 1.27)
			)
			(justify left bottom)
		)
	)
	(text "Compatible with Xilinx Platform Cable"
		(exclude_from_sim no)
		(at 39.37 207.645 0)
		(effects
			(font
				(size 1.27 1.27)
			)
			(justify left bottom)
		)
	)
	(text "MODE[2:0]\n000\n001\n010\n100\n101\n110\n111"
		(exclude_from_sim no)
		(at 118.11 111.125 0)
		(effects
			(font
				(size 1.27 1.27)
			)
			(justify left bottom)
		)
	)
	(text "Diode temp sensor"
		(exclude_from_sim no)
		(at 295.91 207.01 0)
		(effects
			(font
				(size 1.27 1.27)
				(thickness 0.254)
				(bold yes)
			)
			(justify left bottom)
		)
	)
	(junction
		(at 186.69 130.81)
		(diameter 0)
		(color 0 0 0 0)
	)
	(junction
		(at 326.39 201.93)
		(diameter 0)
		(color 0 0 0 0)
	)
	(junction
		(at 248.92 114.3)
		(diameter 0)
		(color 0 0 0 0)
	)
	(junction
		(at 110.49 135.89)
		(diameter 0)
		(color 0 0 0 0)
	)
	(junction
		(at 299.72 180.34)
		(diameter 0)
		(color 0 0 0 0)
	)
	(junction
		(at 118.11 133.35)
		(diameter 0)
		(color 0 0 0 0)
	)
	(junction
		(at 360.68 142.24)
		(diameter 0)
		(color 0 0 0 0)
	)
	(junction
		(at 71.12 224.79)
		(diameter 0)
		(color 0 0 0 0)
	)
	(junction
		(at 38.1 227.33)
		(diameter 0)
		(color 0 0 0 0)
	)
	(junction
		(at 270.51 135.89)
		(diameter 0)
		(color 0 0 0 0)
	)
	(junction
		(at 347.98 139.7)
		(diameter 0)
		(color 0 0 0 0)
	)
	(junction
		(at 350.52 190.5)
		(diameter 0)
		(color 0 0 0 0)
	)
	(junction
		(at 190.5 135.89)
		(diameter 0)
		(color 0 0 0 0)
	)
	(junction
		(at 82.55 135.89)
		(diameter 0)
		(color 0 0 0 0)
	)
	(junction
		(at 66.04 229.87)
		(diameter 0)
		(color 0 0 0 0)
	)
	(junction
		(at 181.61 68.58)
		(diameter 0)
		(color 0 0 0 0)
	)
	(junction
		(at 181.61 78.74)
		(diameter 0)
		(color 0 0 0 0)
	)
	(junction
		(at 125.73 130.81)
		(diameter 0)
		(color 0 0 0 0)
	)
	(junction
		(at 284.48 129.54)
		(diameter 0)
		(color 0 0 0 0)
	)
	(junction
		(at 158.75 95.25)
		(diameter 0)
		(color 0 0 0 0)
	)
	(junction
		(at 189.23 68.58)
		(diameter 0)
		(color 0 0 0 0)
	)
	(junction
		(at 270.51 146.05)
		(diameter 0)
		(color 0 0 0 0)
	)
	(junction
		(at 38.1 232.41)
		(diameter 0)
		(color 0 0 0 0)
	)
	(junction
		(at 38.1 243.84)
		(diameter 0)
		(color 0 0 0 0)
	)
	(junction
		(at 313.69 193.04)
		(diameter 0)
		(color 0 0 0 0)
	)
	(junction
		(at 38.1 224.79)
		(diameter 0)
		(color 0 0 0 0)
	)
	(junction
		(at 38.1 237.49)
		(diameter 0)
		(color 0 0 0 0)
	)
	(junction
		(at 82.55 133.35)
		(diameter 0)
		(color 0 0 0 0)
	)
	(junction
		(at 283.21 127)
		(diameter 0)
		(color 0 0 0 0)
	)
	(junction
		(at 299.72 190.5)
		(diameter 0)
		(color 0 0 0 0)
	)
	(junction
		(at 238.76 124.46)
		(diameter 0)
		(color 0 0 0 0)
	)
	(junction
		(at 173.99 68.58)
		(diameter 0)
		(color 0 0 0 0)
	)
	(junction
		(at 259.08 129.54)
		(diameter 0)
		(color 0 0 0 0)
	)
	(junction
		(at 68.58 227.33)
		(diameter 0)
		(color 0 0 0 0)
	)
	(junction
		(at 173.99 78.74)
		(diameter 0)
		(color 0 0 0 0)
	)
	(junction
		(at 38.1 229.87)
		(diameter 0)
		(color 0 0 0 0)
	)
	(junction
		(at 118.11 119.38)
		(diameter 0)
		(color 0 0 0 0)
	)
	(junction
		(at 38.1 234.95)
		(diameter 0)
		(color 0 0 0 0)
	)
	(junction
		(at 280.67 124.46)
		(diameter 0)
		(color 0 0 0 0)
	)
	(junction
		(at 185.42 128.27)
		(diameter 0)
		(color 0 0 0 0)
	)
	(junction
		(at 63.5 232.41)
		(diameter 0)
		(color 0 0 0 0)
	)
	(junction
		(at 189.23 133.35)
		(diameter 0)
		(color 0 0 0 0)
	)
	(junction
		(at 248.92 127)
		(diameter 0)
		(color 0 0 0 0)
	)
	(junction
		(at 82.55 138.43)
		(diameter 0)
		(color 0 0 0 0)
	)
	(junction
		(at 238.76 114.3)
		(diameter 0)
		(color 0 0 0 0)
	)
	(junction
		(at 312.42 163.83)
		(diameter 0)
		(color 0 0 0 0)
	)
	(junction
		(at 299.72 163.83)
		(diameter 0)
		(color 0 0 0 0)
	)
	(junction
		(at 261.62 146.05)
		(diameter 0)
		(color 0 0 0 0)
	)
	(no_connect
		(at 200.66 151.13)
	)
	(no_connect
		(at 233.68 135.89)
	)
	(no_connect
		(at 233.68 133.35)
	)
	(bus_entry
		(at 158.75 105.41)
		(size 1.27 1.27)
		(stroke
			(width 0)
			(type default)
		)
	)
	(bus_entry
		(at 86.36 222.25)
		(size -2.54 2.54)
		(stroke
			(width 0)
			(type default)
		)
	)
	(bus_entry
		(at 86.36 224.79)
		(size -2.54 2.54)
		(stroke
			(width 0)
			(type default)
		)
	)
	(bus_entry
		(at 158.75 107.95)
		(size 1.27 1.27)
		(stroke
			(width 0)
			(type default)
		)
	)
	(bus_entry
		(at 184.15 140.97)
		(size 1.27 -1.27)
		(stroke
			(width 0)
			(type default)
		)
	)
	(bus_entry
		(at 251.46 101.6)
		(size 1.27 1.27)
		(stroke
			(width 0)
			(type default)
		)
	)
	(bus_entry
		(at 158.75 110.49)
		(size 1.27 1.27)
		(stroke
			(width 0)
			(type default)
		)
	)
	(bus_entry
		(at 86.36 222.25)
		(size -2.54 2.54)
		(stroke
			(width 0)
			(type default)
		)
	)
	(bus_entry
		(at 86.36 227.33)
		(size -2.54 2.54)
		(stroke
			(width 0)
			(type default)
		)
	)
	(bus_entry
		(at 163.83 128.27)
		(size 1.27 0)
		(stroke
			(width 0)
			(type default)
		)
	)
	(bus_entry
		(at 350.52 182.88)
		(size -1.27 1.27)
		(stroke
			(width 0)
			(type default)
		)
	)
	(bus_entry
		(at 86.36 229.87)
		(size -2.54 2.54)
		(stroke
			(width 0)
			(type default)
		)
	)
	(bus_entry
		(at 381 195.58)
		(size 1.27 0)
		(stroke
			(width 0)
			(type default)
		)
	)
	(bus_entry
		(at 158.75 113.03)
		(size 1.27 1.27)
		(stroke
			(width 0)
			(type default)
		)
	)
	(bus_entry
		(at 251.46 99.06)
		(size 1.27 1.27)
		(stroke
			(width 0)
			(type default)
		)
	)
	(bus_entry
		(at 251.46 104.14)
		(size 1.27 1.27)
		(stroke
			(width 0)
			(type default)
		)
	)
	(bus_entry
		(at 184.15 143.51)
		(size 1.27 -1.27)
		(stroke
			(width 0)
			(type default)
		)
	)
	(bus_entry
		(at 184.15 148.59)
		(size 1.27 -1.27)
		(stroke
			(width 0)
			(type default)
		)
	)
	(bus_entry
		(at 184.15 146.05)
		(size 1.27 -1.27)
		(stroke
			(width 0)
			(type default)
		)
	)
	(bus_entry
		(at 86.36 232.41)
		(size -2.54 2.54)
		(stroke
			(width 0)
			(type default)
		)
	)
	(bus_entry
		(at 86.36 229.87)
		(size -2.54 2.54)
		(stroke
			(width 0)
			(type default)
		)
	)
	(bus_entry
		(at 350.52 185.42)
		(size -1.27 1.27)
		(stroke
			(width 0)
			(type default)
		)
	)
	(bus_entry
		(at 86.36 227.33)
		(size -2.54 2.54)
		(stroke
			(width 0)
			(type default)
		)
	)
	(bus_entry
		(at 86.36 224.79)
		(size -2.54 2.54)
		(stroke
			(width 0)
			(type default)
		)
	)
	(bus
		(pts
			(xy 350.52 170.18) (xy 351.79 168.91)
		)
		(stroke
			(width 0)
			(type default)
		)
	)
	(wire
		(pts
			(xy 270.51 143.51) (xy 270.51 146.05)
		)
		(stroke
			(width 0)
			(type default)
		)
	)
	(wire
		(pts
			(xy 316.23 184.15) (xy 307.34 184.15)
		)
		(stroke
			(width 0)
			(type default)
		)
	)
	(wire
		(pts
			(xy 355.6 185.42) (xy 355.6 190.5)
		)
		(stroke
			(width 0)
			(type default)
		)
	)
	(wire
		(pts
			(xy 160.02 111.76) (xy 180.34 111.76)
		)
		(stroke
			(width 0)
			(type default)
		)
	)
	(wire
		(pts
			(xy 200.66 147.32) (xy 185.42 147.32)
		)
		(stroke
			(width 0)
			(type default)
		)
	)
	(wire
		(pts
			(xy 163.83 66.04) (xy 163.83 68.58)
		)
		(stroke
			(width 0)
			(type default)
		)
	)
	(wire
		(pts
			(xy 326.39 114.3) (xy 326.39 116.84)
		)
		(stroke
			(width 0)
			(type default)
		)
	)
	(wire
		(pts
			(xy 173.99 78.74) (xy 173.99 76.2)
		)
		(stroke
			(width 0)
			(type default)
		)
	)
	(wire
		(pts
			(xy 270.51 135.89) (xy 270.51 138.43)
		)
		(stroke
			(width 0)
			(type default)
		)
	)
	(wire
		(pts
			(xy 316.23 190.5) (xy 313.69 190.5)
		)
		(stroke
			(width 0)
			(type default)
		)
	)
	(wire
		(pts
			(xy 238.76 114.3) (xy 248.92 114.3)
		)
		(stroke
			(width 0)
			(type default)
		)
	)
	(wire
		(pts
			(xy 248.92 127) (xy 248.92 120.65)
		)
		(stroke
			(width 0)
			(type default)
		)
	)
	(wire
		(pts
			(xy 200.66 139.7) (xy 185.42 139.7)
		)
		(stroke
			(width 0)
			(type default)
		)
	)
	(wire
		(pts
			(xy 189.23 68.58) (xy 198.12 68.58)
		)
		(stroke
			(width 0)
			(type default)
		)
	)
	(wire
		(pts
			(xy 60.96 245.11) (xy 60.96 243.84)
		)
		(stroke
			(width 0)
			(type default)
		)
	)
	(wire
		(pts
			(xy 200.66 144.78) (xy 185.42 144.78)
		)
		(stroke
			(width 0)
			(type default)
		)
	)
	(wire
		(pts
			(xy 39.37 232.41) (xy 38.1 232.41)
		)
		(stroke
			(width 0)
			(type default)
		)
	)
	(wire
		(pts
			(xy 125.73 130.81) (xy 186.69 130.81)
		)
		(stroke
			(width 0)
			(type default)
		)
	)
	(wire
		(pts
			(xy 254 146.05) (xy 233.68 146.05)
		)
		(stroke
			(width 0)
			(type default)
		)
	)
	(bus
		(pts
			(xy 158.75 95.25) (xy 250.19 95.25)
		)
		(stroke
			(width 0)
			(type default)
		)
	)
	(wire
		(pts
			(xy 82.55 138.43) (xy 82.55 142.24)
		)
		(stroke
			(width 0)
			(type default)
		)
	)
	(wire
		(pts
			(xy 278.13 100.33) (xy 284.48 100.33)
		)
		(stroke
			(width 0)
			(type default)
		)
	)
	(wire
		(pts
			(xy 254 184.15) (xy 295.91 184.15)
		)
		(stroke
			(width 0)
			(type default)
		)
	)
	(wire
		(pts
			(xy 248.92 114.3) (xy 259.08 114.3)
		)
		(stroke
			(width 0)
			(type default)
		)
	)
	(wire
		(pts
			(xy 326.39 163.83) (xy 312.42 163.83)
		)
		(stroke
			(width 0)
			(type default)
		)
	)
	(wire
		(pts
			(xy 252.73 100.33) (xy 274.32 100.33)
		)
		(stroke
			(width 0)
			(type default)
		)
	)
	(wire
		(pts
			(xy 326.39 116.84) (xy 330.2 116.84)
		)
		(stroke
			(width 0)
			(type default)
		)
	)
	(wire
		(pts
			(xy 283.21 102.87) (xy 283.21 127)
		)
		(stroke
			(width 0)
			(type default)
		)
	)
	(bus
		(pts
			(xy 158.75 105.41) (xy 158.75 107.95)
		)
		(stroke
			(width 0)
			(type default)
		)
	)
	(wire
		(pts
			(xy 39.37 222.25) (xy 38.1 222.25)
		)
		(stroke
			(width 0)
			(type default)
		)
	)
	(wire
		(pts
			(xy 118.11 119.38) (xy 118.11 118.11)
		)
		(stroke
			(width 0)
			(type default)
		)
	)
	(wire
		(pts
			(xy 82.55 133.35) (xy 82.55 135.89)
		)
		(stroke
			(width 0)
			(type default)
		)
	)
	(wire
		(pts
			(xy 278.13 102.87) (xy 283.21 102.87)
		)
		(stroke
			(width 0)
			(type default)
		)
	)
	(wire
		(pts
			(xy 38.1 243.84) (xy 60.96 243.84)
		)
		(stroke
			(width 0)
			(type default)
		)
	)
	(wire
		(pts
			(xy 270.51 146.05) (xy 276.86 146.05)
		)
		(stroke
			(width 0)
			(type default)
		)
	)
	(wire
		(pts
			(xy 267.97 146.05) (xy 270.51 146.05)
		)
		(stroke
			(width 0)
			(type default)
		)
	)
	(wire
		(pts
			(xy 312.42 172.72) (xy 312.42 180.34)
		)
		(stroke
			(width 0)
			(type default)
		)
	)
	(wire
		(pts
			(xy 125.73 119.38) (xy 125.73 121.92)
		)
		(stroke
			(width 0)
			(type default)
		)
	)
	(wire
		(pts
			(xy 198.12 124.46) (xy 198.12 68.58)
		)
		(stroke
			(width 0)
			(type default)
		)
	)
	(wire
		(pts
			(xy 326.39 173.99) (xy 326.39 163.83)
		)
		(stroke
			(width 0)
			(type default)
		)
	)
	(wire
		(pts
			(xy 276.86 139.7) (xy 276.86 135.89)
		)
		(stroke
			(width 0)
			(type default)
		)
	)
	(bus
		(pts
			(xy 163.83 128.27) (xy 162.56 128.27)
		)
		(stroke
			(width 0)
			(type default)
		)
	)
	(wire
		(pts
			(xy 280.67 124.46) (xy 311.15 124.46)
		)
		(stroke
			(width 0)
			(type default)
		)
	)
	(wire
		(pts
			(xy 165.1 128.27) (xy 185.42 128.27)
		)
		(stroke
			(width 0)
			(type default)
		)
	)
	(wire
		(pts
			(xy 313.69 201.93) (xy 326.39 201.93)
		)
		(stroke
			(width 0)
			(type default)
		)
	)
	(wire
		(pts
			(xy 299.72 180.34) (xy 299.72 182.88)
		)
		(stroke
			(width 0)
			(type default)
		)
	)
	(wire
		(pts
			(xy 360.68 142.24) (xy 360.68 144.78)
		)
		(stroke
			(width 0)
			(type default)
		)
	)
	(wire
		(pts
			(xy 49.53 234.95) (xy 83.82 234.95)
		)
		(stroke
			(width 0)
			(type default)
		)
	)
	(wire
		(pts
			(xy 189.23 78.74) (xy 189.23 76.2)
		)
		(stroke
			(width 0)
			(type default)
		)
	)
	(wire
		(pts
			(xy 276.86 142.24) (xy 288.29 142.24)
		)
		(stroke
			(width 0)
			(type default)
		)
	)
	(wire
		(pts
			(xy 184.15 106.68) (xy 190.5 106.68)
		)
		(stroke
			(width 0)
			(type default)
		)
	)
	(wire
		(pts
			(xy 326.39 95.25) (xy 326.39 92.71)
		)
		(stroke
			(width 0)
			(type default)
		)
	)
	(wire
		(pts
			(xy 238.76 114.3) (xy 238.76 115.57)
		)
		(stroke
			(width 0)
			(type default)
		)
	)
	(bus
		(pts
			(xy 184.15 151.13) (xy 184.15 148.59)
		)
		(stroke
			(width 0)
			(type default)
		)
	)
	(wire
		(pts
			(xy 335.28 95.25) (xy 339.09 95.25)
		)
		(stroke
			(width 0)
			(type default)
		)
	)
	(wire
		(pts
			(xy 336.55 190.5) (xy 350.52 190.5)
		)
		(stroke
			(width 0)
			(type default)
		)
	)
	(wire
		(pts
			(xy 347.98 139.7) (xy 349.25 139.7)
		)
		(stroke
			(width 0)
			(type default)
		)
	)
	(wire
		(pts
			(xy 270.51 135.89) (xy 259.08 135.89)
		)
		(stroke
			(width 0)
			(type default)
		)
	)
	(wire
		(pts
			(xy 307.34 180.34) (xy 299.72 180.34)
		)
		(stroke
			(width 0)
			(type default)
		)
	)
	(wire
		(pts
			(xy 38.1 224.79) (xy 38.1 227.33)
		)
		(stroke
			(width 0)
			(type default)
		)
	)
	(wire
		(pts
			(xy 360.68 142.24) (xy 360.68 139.7)
		)
		(stroke
			(width 0)
			(type default)
		)
	)
	(wire
		(pts
			(xy 299.72 163.83) (xy 299.72 166.37)
		)
		(stroke
			(width 0)
			(type default)
		)
	)
	(bus
		(pts
			(xy 184.15 143.51) (xy 184.15 140.97)
		)
		(stroke
			(width 0)
			(type default)
		)
	)
	(wire
		(pts
			(xy 186.69 111.76) (xy 186.69 130.81)
		)
		(stroke
			(width 0)
			(type default)
		)
	)
	(wire
		(pts
			(xy 259.08 114.3) (xy 259.08 115.57)
		)
		(stroke
			(width 0)
			(type default)
		)
	)
	(bus
		(pts
			(xy 86.36 222.25) (xy 86.36 224.79)
		)
		(stroke
			(width 0)
			(type default)
		)
	)
	(bus
		(pts
			(xy 86.36 222.25) (xy 86.36 219.71)
		)
		(stroke
			(width 0)
			(type default)
		)
	)
	(wire
		(pts
			(xy 316.23 180.34) (xy 312.42 180.34)
		)
		(stroke
			(width 0)
			(type default)
		)
	)
	(wire
		(pts
			(xy 344.17 95.25) (xy 346.71 95.25)
		)
		(stroke
			(width 0)
			(type default)
		)
	)
	(bus
		(pts
			(xy 86.36 229.87) (xy 86.36 232.41)
		)
		(stroke
			(width 0)
			(type default)
		)
	)
	(wire
		(pts
			(xy 284.48 129.54) (xy 341.63 129.54)
		)
		(stroke
			(width 0)
			(type default)
		)
	)
	(wire
		(pts
			(xy 233.68 139.7) (xy 259.08 139.7)
		)
		(stroke
			(width 0)
			(type default)
		)
	)
	(wire
		(pts
			(xy 295.91 190.5) (xy 295.91 186.69)
		)
		(stroke
			(width 0)
			(type default)
		)
	)
	(wire
		(pts
			(xy 233.68 124.46) (xy 238.76 124.46)
		)
		(stroke
			(width 0)
			(type default)
		)
	)
	(wire
		(pts
			(xy 359.41 139.7) (xy 360.68 139.7)
		)
		(stroke
			(width 0)
			(type default)
		)
	)
	(wire
		(pts
			(xy 110.49 119.38) (xy 118.11 119.38)
		)
		(stroke
			(width 0)
			(type default)
		)
	)
	(wire
		(pts
			(xy 341.63 129.54) (xy 341.63 139.7)
		)
		(stroke
			(width 0)
			(type default)
		)
	)
	(wire
		(pts
			(xy 118.11 133.35) (xy 189.23 133.35)
		)
		(stroke
			(width 0)
			(type default)
		)
	)
	(wire
		(pts
			(xy 361.95 119.38) (xy 361.95 116.84)
		)
		(stroke
			(width 0)
			(type default)
		)
	)
	(wire
		(pts
			(xy 259.08 142.24) (xy 259.08 146.05)
		)
		(stroke
			(width 0)
			(type default)
		)
	)
	(wire
		(pts
			(xy 184.15 109.22) (xy 189.23 109.22)
		)
		(stroke
			(width 0)
			(type default)
		)
	)
	(wire
		(pts
			(xy 49.53 229.87) (xy 66.04 229.87)
		)
		(stroke
			(width 0)
			(type default)
		)
	)
	(wire
		(pts
			(xy 313.69 190.5) (xy 313.69 193.04)
		)
		(stroke
			(width 0)
			(type default)
		)
	)
	(wire
		(pts
			(xy 99.06 130.81) (xy 125.73 130.81)
		)
		(stroke
			(width 0)
			(type default)
		)
	)
	(bus
		(pts
			(xy 251.46 99.06) (xy 251.46 101.6)
		)
		(stroke
			(width 0)
			(type default)
		)
	)
	(wire
		(pts
			(xy 361.95 116.84) (xy 359.41 116.84)
		)
		(stroke
			(width 0)
			(type default)
		)
	)
	(wire
		(pts
			(xy 238.76 120.65) (xy 238.76 124.46)
		)
		(stroke
			(width 0)
			(type default)
		)
	)
	(wire
		(pts
			(xy 66.04 229.87) (xy 83.82 229.87)
		)
		(stroke
			(width 0)
			(type default)
		)
	)
	(wire
		(pts
			(xy 350.52 195.58) (xy 381 195.58)
		)
		(stroke
			(width 0)
			(type default)
		)
	)
	(wire
		(pts
			(xy 86.36 130.81) (xy 82.55 130.81)
		)
		(stroke
			(width 0)
			(type default)
		)
	)
	(wire
		(pts
			(xy 190.5 135.89) (xy 200.66 135.89)
		)
		(stroke
			(width 0)
			(type default)
		)
	)
	(wire
		(pts
			(xy 259.08 129.54) (xy 259.08 120.65)
		)
		(stroke
			(width 0)
			(type default)
		)
	)
	(wire
		(pts
			(xy 283.21 127) (xy 355.6 127)
		)
		(stroke
			(width 0)
			(type default)
		)
	)
	(wire
		(pts
			(xy 38.1 243.84) (xy 38.1 248.92)
		)
		(stroke
			(width 0)
			(type default)
		)
	)
	(wire
		(pts
			(xy 299.72 187.96) (xy 299.72 190.5)
		)
		(stroke
			(width 0)
			(type default)
		)
	)
	(wire
		(pts
			(xy 344.17 116.84) (xy 346.71 116.84)
		)
		(stroke
			(width 0)
			(type default)
		)
	)
	(wire
		(pts
			(xy 248.92 127) (xy 283.21 127)
		)
		(stroke
			(width 0)
			(type default)
		)
	)
	(wire
		(pts
			(xy 110.49 121.92) (xy 110.49 119.38)
		)
		(stroke
			(width 0)
			(type default)
		)
	)
	(wire
		(pts
			(xy 82.55 130.81) (xy 82.55 133.35)
		)
		(stroke
			(width 0)
			(type default)
		)
	)
	(wire
		(pts
			(xy 38.1 232.41) (xy 38.1 234.95)
		)
		(stroke
			(width 0)
			(type default)
		)
	)
	(bus
		(pts
			(xy 158.75 110.49) (xy 158.75 113.03)
		)
		(stroke
			(width 0)
			(type default)
		)
	)
	(wire
		(pts
			(xy 52.07 237.49) (xy 49.53 237.49)
		)
		(stroke
			(width 0)
			(type default)
		)
	)
	(wire
		(pts
			(xy 163.83 68.58) (xy 173.99 68.58)
		)
		(stroke
			(width 0)
			(type default)
		)
	)
	(wire
		(pts
			(xy 355.6 102.87) (xy 355.6 105.41)
		)
		(stroke
			(width 0)
			(type default)
		)
	)
	(bus
		(pts
			(xy 100.33 218.44) (xy 88.9 218.44)
		)
		(stroke
			(width 0)
			(type default)
		)
	)
	(wire
		(pts
			(xy 355.6 124.46) (xy 355.6 127)
		)
		(stroke
			(width 0)
			(type default)
		)
	)
	(wire
		(pts
			(xy 347.98 139.7) (xy 347.98 142.24)
		)
		(stroke
			(width 0)
			(type default)
		)
	)
	(wire
		(pts
			(xy 190.5 106.68) (xy 190.5 135.89)
		)
		(stroke
			(width 0)
			(type default)
		)
	)
	(wire
		(pts
			(xy 173.99 71.12) (xy 173.99 68.58)
		)
		(stroke
			(width 0)
			(type default)
		)
	)
	(wire
		(pts
			(xy 71.12 224.79) (xy 83.82 224.79)
		)
		(stroke
			(width 0)
			(type default)
		)
	)
	(wire
		(pts
			(xy 299.72 190.5) (xy 295.91 190.5)
		)
		(stroke
			(width 0)
			(type default)
		)
	)
	(bus
		(pts
			(xy 156.21 95.25) (xy 158.75 95.25)
		)
		(stroke
			(width 0)
			(type default)
		)
	)
	(wire
		(pts
			(xy 350.52 190.5) (xy 355.6 190.5)
		)
		(stroke
			(width 0)
			(type default)
		)
	)
	(wire
		(pts
			(xy 82.55 133.35) (xy 86.36 133.35)
		)
		(stroke
			(width 0)
			(type default)
		)
	)
	(bus
		(pts
			(xy 350.52 170.18) (xy 350.52 182.88)
		)
		(stroke
			(width 0)
			(type default)
		)
	)
	(wire
		(pts
			(xy 189.23 109.22) (xy 189.23 133.35)
		)
		(stroke
			(width 0)
			(type default)
		)
	)
	(wire
		(pts
			(xy 63.5 232.41) (xy 83.82 232.41)
		)
		(stroke
			(width 0)
			(type default)
		)
	)
	(wire
		(pts
			(xy 173.99 68.58) (xy 181.61 68.58)
		)
		(stroke
			(width 0)
			(type default)
		)
	)
	(bus
		(pts
			(xy 158.75 107.95) (xy 158.75 110.49)
		)
		(stroke
			(width 0)
			(type default)
		)
	)
	(wire
		(pts
			(xy 38.1 229.87) (xy 38.1 232.41)
		)
		(stroke
			(width 0)
			(type default)
		)
	)
	(wire
		(pts
			(xy 311.15 105.41) (xy 355.6 105.41)
		)
		(stroke
			(width 0)
			(type default)
		)
	)
	(wire
		(pts
			(xy 259.08 146.05) (xy 261.62 146.05)
		)
		(stroke
			(width 0)
			(type default)
		)
	)
	(polyline
		(pts
			(xy 118.11 96.52) (xy 118.11 111.76)
		)
		(stroke
			(width 0.1016)
			(type solid)
		)
	)
	(bus
		(pts
			(xy 350.52 182.88) (xy 350.52 185.42)
		)
		(stroke
			(width 0)
			(type default)
		)
	)
	(wire
		(pts
			(xy 347.98 142.24) (xy 349.25 142.24)
		)
		(stroke
			(width 0)
			(type default)
		)
	)
	(wire
		(pts
			(xy 336.55 186.69) (xy 349.25 186.69)
		)
		(stroke
			(width 0)
			(type default)
		)
	)
	(wire
		(pts
			(xy 82.55 135.89) (xy 82.55 138.43)
		)
		(stroke
			(width 0)
			(type default)
		)
	)
	(wire
		(pts
			(xy 313.69 193.04) (xy 316.23 193.04)
		)
		(stroke
			(width 0)
			(type default)
		)
	)
	(wire
		(pts
			(xy 299.72 163.83) (xy 312.42 163.83)
		)
		(stroke
			(width 0)
			(type default)
		)
	)
	(wire
		(pts
			(xy 110.49 135.89) (xy 190.5 135.89)
		)
		(stroke
			(width 0)
			(type default)
		)
	)
	(wire
		(pts
			(xy 307.34 186.69) (xy 307.34 190.5)
		)
		(stroke
			(width 0)
			(type default)
		)
	)
	(wire
		(pts
			(xy 189.23 78.74) (xy 181.61 78.74)
		)
		(stroke
			(width 0)
			(type default)
		)
	)
	(wire
		(pts
			(xy 361.95 97.79) (xy 361.95 95.25)
		)
		(stroke
			(width 0)
			(type default)
		)
	)
	(wire
		(pts
			(xy 233.68 127) (xy 248.92 127)
		)
		(stroke
			(width 0)
			(type default)
		)
	)
	(wire
		(pts
			(xy 238.76 113.03) (xy 238.76 114.3)
		)
		(stroke
			(width 0)
			(type default)
		)
	)
	(wire
		(pts
			(xy 160.02 109.22) (xy 180.34 109.22)
		)
		(stroke
			(width 0)
			(type default)
		)
	)
	(wire
		(pts
			(xy 254 184.15) (xy 254 146.05)
		)
		(stroke
			(width 0)
			(type default)
		)
	)
	(wire
		(pts
			(xy 311.15 124.46) (xy 311.15 105.41)
		)
		(stroke
			(width 0)
			(type default)
		)
	)
	(wire
		(pts
			(xy 38.1 234.95) (xy 38.1 237.49)
		)
		(stroke
			(width 0)
			(type default)
		)
	)
	(wire
		(pts
			(xy 361.95 95.25) (xy 359.41 95.25)
		)
		(stroke
			(width 0)
			(type default)
		)
	)
	(wire
		(pts
			(xy 233.68 129.54) (xy 259.08 129.54)
		)
		(stroke
			(width 0)
			(type default)
		)
	)
	(wire
		(pts
			(xy 284.48 100.33) (xy 284.48 129.54)
		)
		(stroke
			(width 0)
			(type default)
		)
	)
	(wire
		(pts
			(xy 99.06 133.35) (xy 118.11 133.35)
		)
		(stroke
			(width 0)
			(type default)
		)
	)
	(wire
		(pts
			(xy 335.28 116.84) (xy 339.09 116.84)
		)
		(stroke
			(width 0)
			(type default)
		)
	)
	(wire
		(pts
			(xy 233.68 142.24) (xy 259.08 142.24)
		)
		(stroke
			(width 0)
			(type default)
		)
	)
	(wire
		(pts
			(xy 55.88 220.98) (xy 55.88 222.25)
		)
		(stroke
			(width 0)
			(type default)
		)
	)
	(wire
		(pts
			(xy 185.42 114.3) (xy 185.42 128.27)
		)
		(stroke
			(width 0)
			(type default)
		)
	)
	(wire
		(pts
			(xy 181.61 78.74) (xy 173.99 78.74)
		)
		(stroke
			(width 0)
			(type default)
		)
	)
	(wire
		(pts
			(xy 189.23 71.12) (xy 189.23 68.58)
		)
		(stroke
			(width 0)
			(type default)
		)
	)
	(wire
		(pts
			(xy 200.66 142.24) (xy 185.42 142.24)
		)
		(stroke
			(width 0)
			(type default)
		)
	)
	(bus
		(pts
			(xy 251.46 96.52) (xy 250.19 95.25)
		)
		(stroke
			(width 0)
			(type default)
		)
	)
	(wire
		(pts
			(xy 181.61 76.2) (xy 181.61 78.74)
		)
		(stroke
			(width 0)
			(type default)
		)
	)
	(wire
		(pts
			(xy 118.11 119.38) (xy 125.73 119.38)
		)
		(stroke
			(width 0)
			(type default)
		)
	)
	(wire
		(pts
			(xy 251.46 186.69) (xy 295.91 186.69)
		)
		(stroke
			(width 0)
			(type default)
		)
	)
	(wire
		(pts
			(xy 251.46 148.59) (xy 251.46 186.69)
		)
		(stroke
			(width 0)
			(type default)
		)
	)
	(wire
		(pts
			(xy 160.02 106.68) (xy 180.34 106.68)
		)
		(stroke
			(width 0)
			(type default)
		)
	)
	(wire
		(pts
			(xy 336.55 184.15) (xy 349.25 184.15)
		)
		(stroke
			(width 0)
			(type default)
		)
	)
	(wire
		(pts
			(xy 181.61 68.58) (xy 181.61 71.12)
		)
		(stroke
			(width 0)
			(type default)
		)
	)
	(wire
		(pts
			(xy 261.62 146.05) (xy 264.16 146.05)
		)
		(stroke
			(width 0)
			(type default)
		)
	)
	(wire
		(pts
			(xy 68.58 227.33) (xy 83.82 227.33)
		)
		(stroke
			(width 0)
			(type default)
		)
	)
	(wire
		(pts
			(xy 184.15 111.76) (xy 186.69 111.76)
		)
		(stroke
			(width 0)
			(type default)
		)
	)
	(bus
		(pts
			(xy 251.46 101.6) (xy 251.46 104.14)
		)
		(stroke
			(width 0)
			(type default)
		)
	)
	(wire
		(pts
			(xy 38.1 237.49) (xy 38.1 243.84)
		)
		(stroke
			(width 0)
			(type default)
		)
	)
	(wire
		(pts
			(xy 71.12 224.79) (xy 71.12 245.11)
		)
		(stroke
			(width 0)
			(type default)
		)
	)
	(wire
		(pts
			(xy 299.72 171.45) (xy 299.72 173.99)
		)
		(stroke
			(width 0)
			(type default)
		)
	)
	(wire
		(pts
			(xy 313.69 193.04) (xy 313.69 201.93)
		)
		(stroke
			(width 0)
			(type default)
		)
	)
	(wire
		(pts
			(xy 49.53 232.41) (xy 63.5 232.41)
		)
		(stroke
			(width 0)
			(type default)
		)
	)
	(wire
		(pts
			(xy 185.42 128.27) (xy 200.66 128.27)
		)
		(stroke
			(width 0)
			(type default)
		)
	)
	(wire
		(pts
			(xy 49.53 224.79) (xy 71.12 224.79)
		)
		(stroke
			(width 0)
			(type default)
		)
	)
	(wire
		(pts
			(xy 280.67 105.41) (xy 280.67 124.46)
		)
		(stroke
			(width 0)
			(type default)
		)
	)
	(wire
		(pts
			(xy 68.58 227.33) (xy 68.58 245.11)
		)
		(stroke
			(width 0)
			(type default)
		)
	)
	(wire
		(pts
			(xy 261.62 146.05) (xy 261.62 147.32)
		)
		(stroke
			(width 0)
			(type default)
		)
	)
	(wire
		(pts
			(xy 233.68 148.59) (xy 251.46 148.59)
		)
		(stroke
			(width 0)
			(type default)
		)
	)
	(wire
		(pts
			(xy 326.39 200.66) (xy 326.39 201.93)
		)
		(stroke
			(width 0)
			(type default)
		)
	)
	(wire
		(pts
			(xy 186.69 130.81) (xy 200.66 130.81)
		)
		(stroke
			(width 0)
			(type default)
		)
	)
	(wire
		(pts
			(xy 200.66 124.46) (xy 198.12 124.46)
		)
		(stroke
			(width 0)
			(type default)
		)
	)
	(wire
		(pts
			(xy 359.41 142.24) (xy 360.68 142.24)
		)
		(stroke
			(width 0)
			(type default)
		)
	)
	(wire
		(pts
			(xy 49.53 227.33) (xy 68.58 227.33)
		)
		(stroke
			(width 0)
			(type default)
		)
	)
	(polyline
		(pts
			(xy 99.06 96.52) (xy 128.27 96.52)
		)
		(stroke
			(width 0.1016)
			(type solid)
		)
	)
	(bus
		(pts
			(xy 158.75 95.25) (xy 158.75 105.41)
		)
		(stroke
			(width 0)
			(type default)
		)
	)
	(wire
		(pts
			(xy 299.72 180.34) (xy 295.91 180.34)
		)
		(stroke
			(width 0)
			(type default)
		)
	)
	(wire
		(pts
			(xy 299.72 162.56) (xy 299.72 163.83)
		)
		(stroke
			(width 0)
			(type default)
		)
	)
	(wire
		(pts
			(xy 248.92 114.3) (xy 248.92 115.57)
		)
		(stroke
			(width 0)
			(type default)
		)
	)
	(wire
		(pts
			(xy 49.53 222.25) (xy 55.88 222.25)
		)
		(stroke
			(width 0)
			(type default)
		)
	)
	(wire
		(pts
			(xy 307.34 190.5) (xy 299.72 190.5)
		)
		(stroke
			(width 0)
			(type default)
		)
	)
	(wire
		(pts
			(xy 160.02 114.3) (xy 180.34 114.3)
		)
		(stroke
			(width 0)
			(type default)
		)
	)
	(wire
		(pts
			(xy 295.91 180.34) (xy 295.91 184.15)
		)
		(stroke
			(width 0)
			(type default)
		)
	)
	(wire
		(pts
			(xy 82.55 138.43) (xy 86.36 138.43)
		)
		(stroke
			(width 0)
			(type default)
		)
	)
	(bus
		(pts
			(xy 86.36 227.33) (xy 86.36 229.87)
		)
		(stroke
			(width 0)
			(type default)
		)
	)
	(bus
		(pts
			(xy 179.07 152.4) (xy 182.88 152.4)
		)
		(stroke
			(width 0)
			(type default)
		)
	)
	(wire
		(pts
			(xy 39.37 227.33) (xy 38.1 227.33)
		)
		(stroke
			(width 0)
			(type default)
		)
	)
	(wire
		(pts
			(xy 38.1 222.25) (xy 38.1 224.79)
		)
		(stroke
			(width 0)
			(type default)
		)
	)
	(wire
		(pts
			(xy 184.15 114.3) (xy 185.42 114.3)
		)
		(stroke
			(width 0)
			(type default)
		)
	)
	(bus
		(pts
			(xy 184.15 146.05) (xy 184.15 143.51)
		)
		(stroke
			(width 0)
			(type default)
		)
	)
	(wire
		(pts
			(xy 259.08 129.54) (xy 284.48 129.54)
		)
		(stroke
			(width 0)
			(type default)
		)
	)
	(wire
		(pts
			(xy 326.39 203.2) (xy 326.39 201.93)
		)
		(stroke
			(width 0)
			(type default)
		)
	)
	(bus
		(pts
			(xy 86.36 224.79) (xy 86.36 227.33)
		)
		(stroke
			(width 0)
			(type default)
		)
	)
	(bus
		(pts
			(xy 86.36 219.71) (xy 88.9 218.44)
		)
		(stroke
			(width 0)
			(type default)
		)
	)
	(wire
		(pts
			(xy 312.42 163.83) (xy 312.42 167.64)
		)
		(stroke
			(width 0)
			(type default)
		)
	)
	(wire
		(pts
			(xy 252.73 105.41) (xy 274.32 105.41)
		)
		(stroke
			(width 0)
			(type default)
		)
	)
	(bus
		(pts
			(xy 184.15 148.59) (xy 184.15 146.05)
		)
		(stroke
			(width 0)
			(type default)
		)
	)
	(wire
		(pts
			(xy 326.39 95.25) (xy 330.2 95.25)
		)
		(stroke
			(width 0)
			(type default)
		)
	)
	(wire
		(pts
			(xy 341.63 139.7) (xy 347.98 139.7)
		)
		(stroke
			(width 0)
			(type default)
		)
	)
	(wire
		(pts
			(xy 39.37 224.79) (xy 38.1 224.79)
		)
		(stroke
			(width 0)
			(type default)
		)
	)
	(wire
		(pts
			(xy 355.6 176.53) (xy 355.6 180.34)
		)
		(stroke
			(width 0)
			(type default)
		)
	)
	(bus
		(pts
			(xy 184.15 151.13) (xy 182.88 152.4)
		)
		(stroke
			(width 0)
			(type default)
		)
	)
	(wire
		(pts
			(xy 350.52 190.5) (xy 350.52 191.77)
		)
		(stroke
			(width 0)
			(type default)
		)
	)
	(bus
		(pts
			(xy 251.46 96.52) (xy 251.46 99.06)
		)
		(stroke
			(width 0)
			(type default)
		)
	)
	(wire
		(pts
			(xy 118.11 127) (xy 118.11 133.35)
		)
		(stroke
			(width 0)
			(type default)
		)
	)
	(wire
		(pts
			(xy 276.86 135.89) (xy 270.51 135.89)
		)
		(stroke
			(width 0)
			(type default)
		)
	)
	(wire
		(pts
			(xy 278.13 105.41) (xy 280.67 105.41)
		)
		(stroke
			(width 0)
			(type default)
		)
	)
	(bus
		(pts
			(xy 351.79 168.91) (xy 356.87 168.91)
		)
		(stroke
			(width 0)
			(type default)
		)
	)
	(wire
		(pts
			(xy 252.73 102.87) (xy 274.32 102.87)
		)
		(stroke
			(width 0)
			(type default)
		)
	)
	(wire
		(pts
			(xy 259.08 135.89) (xy 259.08 139.7)
		)
		(stroke
			(width 0)
			(type default)
		)
	)
	(wire
		(pts
			(xy 118.11 119.38) (xy 118.11 121.92)
		)
		(stroke
			(width 0)
			(type default)
		)
	)
	(wire
		(pts
			(xy 63.5 232.41) (xy 63.5 245.11)
		)
		(stroke
			(width 0)
			(type default)
		)
	)
	(wire
		(pts
			(xy 39.37 237.49) (xy 38.1 237.49)
		)
		(stroke
			(width 0)
			(type default)
		)
	)
	(wire
		(pts
			(xy 276.86 139.7) (xy 288.29 139.7)
		)
		(stroke
			(width 0)
			(type default)
		)
	)
	(wire
		(pts
			(xy 39.37 229.87) (xy 38.1 229.87)
		)
		(stroke
			(width 0)
			(type default)
		)
	)
	(wire
		(pts
			(xy 276.86 146.05) (xy 276.86 142.24)
		)
		(stroke
			(width 0)
			(type default)
		)
	)
	(wire
		(pts
			(xy 316.23 186.69) (xy 307.34 186.69)
		)
		(stroke
			(width 0)
			(type default)
		)
	)
	(wire
		(pts
			(xy 181.61 68.58) (xy 189.23 68.58)
		)
		(stroke
			(width 0)
			(type default)
		)
	)
	(wire
		(pts
			(xy 38.1 227.33) (xy 38.1 229.87)
		)
		(stroke
			(width 0)
			(type default)
		)
	)
	(wire
		(pts
			(xy 238.76 124.46) (xy 280.67 124.46)
		)
		(stroke
			(width 0)
			(type default)
		)
	)
	(wire
		(pts
			(xy 307.34 184.15) (xy 307.34 180.34)
		)
		(stroke
			(width 0)
			(type default)
		)
	)
	(bus
		(pts
			(xy 384.81 195.58) (xy 382.27 195.58)
		)
		(stroke
			(width 0)
			(type default)
		)
	)
	(wire
		(pts
			(xy 110.49 135.89) (xy 99.06 135.89)
		)
		(stroke
			(width 0)
			(type default)
		)
	)
	(wire
		(pts
			(xy 110.49 127) (xy 110.49 135.89)
		)
		(stroke
			(width 0)
			(type default)
		)
	)
	(wire
		(pts
			(xy 39.37 234.95) (xy 38.1 234.95)
		)
		(stroke
			(width 0)
			(type default)
		)
	)
	(wire
		(pts
			(xy 66.04 229.87) (xy 66.04 245.11)
		)
		(stroke
			(width 0)
			(type default)
		)
	)
	(wire
		(pts
			(xy 125.73 127) (xy 125.73 130.81)
		)
		(stroke
			(width 0)
			(type default)
		)
	)
	(wire
		(pts
			(xy 189.23 133.35) (xy 200.66 133.35)
		)
		(stroke
			(width 0)
			(type default)
		)
	)
	(wire
		(pts
			(xy 82.55 135.89) (xy 86.36 135.89)
		)
		(stroke
			(width 0)
			(type default)
		)
	)
	(wire
		(pts
			(xy 173.99 78.74) (xy 173.99 80.01)
		)
		(stroke
			(width 0)
			(type default)
		)
	)
	(label "I2C.SCL"
		(at 337.82 186.69 0)
		(effects
			(font
				(size 1.27 1.27)
			)
			(justify left bottom)
		)
	)
	(label "DONE"
		(at 267.97 124.46 0)
		(effects
			(font
				(size 1.27 1.27)
			)
			(justify left bottom)
		)
	)
	(label "MODE2"
		(at 198.12 135.89 180)
		(effects
			(font
				(size 1.27 1.27)
			)
			(justify right bottom)
		)
	)
	(label "FPGA_CFG_DXN"
		(at 234.95 148.59 0)
		(effects
			(font
				(size 1.27 1.27)
			)
			(justify left bottom)
		)
	)
	(label "SYSTEM_FLASH.CLK"
		(at 184.15 128.27 180)
		(effects
			(font
				(size 1.27 1.27)
			)
			(justify right bottom)
		)
	)
	(label "PROGRAM_B"
		(at 267.97 129.54 0)
		(effects
			(font
				(size 1.27 1.27)
			)
			(justify left bottom)
		)
	)
	(label "JTAG{JTAG}"
		(at 100.33 218.44 180)
		(effects
			(font
				(size 1.27 1.27)
			)
			(justify right bottom)
		)
	)
	(label "SUP_MCU.CCLK"
		(at 161.29 114.3 0)
		(effects
			(font
				(size 1.27 1.27)
			)
			(justify left bottom)
		)
	)
	(label "SUP_MCU.PROGRAMB"
		(at 274.32 100.33 180)
		(effects
			(font
				(size 1.27 1.27)
			)
			(justify right bottom)
		)
	)
	(label "FPGA_CFG_DXP"
		(at 234.95 146.05 0)
		(effects
			(font
				(size 1.27 1.27)
			)
			(justify left bottom)
		)
	)
	(label "SUP_MCU.FPGA_M2"
		(at 161.29 106.68 0)
		(effects
			(font
				(size 1.27 1.27)
			)
			(justify left bottom)
		)
	)
	(label "SUP_MCU.DONE"
		(at 274.32 105.41 180)
		(effects
			(font
				(size 1.27 1.27)
			)
			(justify right bottom)
		)
	)
	(label "SUP_MCU.FPGA_M1"
		(at 161.29 109.22 0)
		(effects
			(font
				(size 1.27 1.27)
			)
			(justify left bottom)
		)
	)
	(label "I2C.SDA"
		(at 337.82 184.15 0)
		(effects
			(font
				(size 1.27 1.27)
			)
			(justify left bottom)
		)
	)
	(label "SUP_MCU.FPGA_M0"
		(at 161.29 111.76 0)
		(effects
			(font
				(size 1.27 1.27)
			)
			(justify left bottom)
		)
	)
	(label "SUP_MCU.INITB"
		(at 274.32 102.87 180)
		(effects
			(font
				(size 1.27 1.27)
			)
			(justify right bottom)
		)
	)
	(label "JTAG.TCK"
		(at 198.12 147.32 180)
		(effects
			(font
				(size 1.27 1.27)
			)
			(justify right bottom)
		)
	)
	(label "MODE1"
		(at 198.12 133.35 180)
		(effects
			(font
				(size 1.27 1.27)
			)
			(justify right bottom)
		)
	)
	(label "TEMP_~{ALERT}"
		(at 337.82 190.5 0)
		(effects
			(font
				(size 1.27 1.27)
			)
			(justify left bottom)
		)
	)
	(label "JTAG.TMS"
		(at 198.12 144.78 180)
		(effects
			(font
				(size 1.27 1.27)
			)
			(justify right bottom)
		)
	)
	(label "JTAG.TMS"
		(at 73.66 224.79 0)
		(effects
			(font
				(size 1.27 1.27)
			)
			(justify left bottom)
		)
	)
	(label "JTAG.TDO"
		(at 198.12 142.24 180)
		(effects
			(font
				(size 1.27 1.27)
			)
			(justify right bottom)
		)
	)
	(label "JTAG.TDO"
		(at 73.66 229.87 0)
		(effects
			(font
				(size 1.27 1.27)
			)
			(justify left bottom)
		)
	)
	(label "MODE0"
		(at 198.12 130.81 180)
		(effects
			(font
				(size 1.27 1.27)
			)
			(justify right bottom)
		)
	)
	(label "SUP_MCU.TEMP_ALERT_N"
		(at 356.87 195.58 0)
		(effects
			(font
				(size 1.27 1.27)
			)
			(justify left bottom)
		)
	)
	(label "JTAG.TCK"
		(at 73.66 227.33 0)
		(effects
			(font
				(size 1.27 1.27)
			)
			(justify left bottom)
		)
	)
	(label "JTAG.TDI"
		(at 198.12 139.7 180)
		(effects
			(font
				(size 1.27 1.27)
			)
			(justify right bottom)
		)
	)
	(label "INIT_B"
		(at 267.97 127 0)
		(effects
			(font
				(size 1.27 1.27)
			)
			(justify left bottom)
		)
	)
	(label "JTAG.RST"
		(at 73.66 234.95 0)
		(effects
			(font
				(size 1.27 1.27)
			)
			(justify left bottom)
		)
	)
	(label "JTAG.TDI"
		(at 73.66 232.41 0)
		(effects
			(font
				(size 1.27 1.27)
			)
			(justify left bottom)
		)
	)
	(global_label "VREFN"
		(shape input)
		(at 288.29 142.24 0)
		(fields_autoplaced yes)
		(effects
			(font
				(size 1.27 1.27)
			)
			(justify left)
		)
		(property "Intersheetrefs" "${INTERSHEET_REFS}"
			(at 296.6298 142.1606 0)
			(effects
				(font
					(size 1.27 1.27)
				)
				(justify left)
				(hide yes)
			)
		)
	)
	(global_label "FTDI_DIS"
		(shape input)
		(at 52.07 237.49 0)
		(fields_autoplaced yes)
		(effects
			(font
				(size 1.27 1.27)
			)
			(justify left)
		)
		(property "Intersheetrefs" "${INTERSHEET_REFS}"
			(at 62.466 237.5694 0)
			(effects
				(font
					(size 1.27 1.27)
				)
				(justify left)
				(hide yes)
			)
		)
	)
	(global_label "VREFP"
		(shape input)
		(at 288.29 139.7 0)
		(fields_autoplaced yes)
		(effects
			(font
				(size 1.27 1.27)
			)
			(justify left)
		)
		(property "Intersheetrefs" "${INTERSHEET_REFS}"
			(at 296.5693 139.6206 0)
			(effects
				(font
					(size 1.27 1.27)
				)
				(justify left)
				(hide yes)
			)
		)
	)
	(hierarchical_label "I2C{I2C}"
		(shape bidirectional)
		(at 356.87 168.91 0)
		(effects
			(font
				(size 1.27 1.27)
			)
			(justify left)
		)
	)
	(hierarchical_label "SUP_MCU{SUP-MCU}"
		(shape bidirectional)
		(at 156.21 95.25 180)
		(effects
			(font
				(size 1.27 1.27)
			)
			(justify right)
		)
	)
	(hierarchical_label "JTAG{JTAG}"
		(shape bidirectional)
		(at 179.07 152.4 180)
		(effects
			(font
				(size 1.27 1.27)
			)
			(justify right)
		)
	)
	(hierarchical_label "SYSTEM_FLASH{SPI-FLASH}"
		(shape bidirectional)
		(at 162.56 128.27 180)
		(effects
			(font
				(size 1.27 1.27)
			)
			(justify right)
		)
	)
	(hierarchical_label "SUP_MCU{SUP-MCU}"
		(shape bidirectional)
		(at 384.81 195.58 0)
		(effects
			(font
				(size 1.27 1.27)
			)
			(justify left)
		)
	)
	(symbol
		(lib_id "antmicroResistors0402:R_330R_0402")
		(at 339.09 95.25 0)
		(unit 1)
		(exclude_from_sim no)
		(in_bom yes)
		(on_board yes)
		(dnp no)
		(property "Reference" "R9"
			(at 341.63 92.71 0)
			(effects
				(font
					(size 1.524 1.524)
				)
			)
		)
		(property "Value" "R_330R_0402"
			(at 359.41 107.95 0)
			(effects
				(font
					(size 1.27 1.27)
					(thickness 0.15)
				)
				(justify left bottom)
				(hide yes)
			)
		)
		(property "Footprint" "antmicro-footprints:R_0402_1005Metric"
			(at 359.41 110.49 0)
			(effects
				(font
					(size 1.27 1.27)
					(thickness 0.15)
				)
				(justify left bottom)
				(hide yes)
			)
		)
		(property "Datasheet" "https://www.bourns.com/docs/product-datasheets/cr.pdf"
			(at 359.41 113.03 0)
			(effects
				(font
					(size 1.27 1.27)
					(thickness 0.15)
				)
				(justify left bottom)
				(hide yes)
			)
		)
		(property "Description" ""
			(at 339.09 95.25 0)
			(effects
				(font
					(size 1.27 1.27)
				)
			)
		)
		(property "Manufacturer" "Bourns"
			(at 359.41 118.11 0)
			(effects
				(font
					(size 1.27 1.27)
					(thickness 0.15)
				)
				(justify left bottom)
				(hide yes)
			)
		)
		(property "MPN" "CR0402-FX-3300GLF"
			(at 359.41 115.57 0)
			(effects
				(font
					(size 1.27 1.27)
					(thickness 0.15)
				)
				(justify left bottom)
				(hide yes)
			)
		)
		(property "Val" "330R"
			(at 341.63 97.79 0)
			(effects
				(font
					(size 1.27 1.27)
					(thickness 0.15)
				)
			)
		)
		(property "License" "Apache-2.0"
			(at 359.41 120.65 0)
			(effects
				(font
					(size 1.27 1.27)
					(thickness 0.15)
				)
				(justify left bottom)
				(hide yes)
			)
		)
		(property "Author" "Antmicro"
			(at 359.41 123.19 0)
			(effects
				(font
					(size 1.27 1.27)
					(thickness 0.15)
				)
				(justify left bottom)
				(hide yes)
			)
		)
		(property "Tolerance" "1%"
			(at 359.41 105.41 0)
			(effects
				(font
					(size 1.27 1.27)
				)
				(justify left bottom)
				(hide yes)
			)
		)
		(pin "1"
		)
		(pin "2"
		)
		(instances
			(project "k410t-devboard"
				(path ""
					(reference "R9")
					(unit 1)
				)
			)
		)
	)
	(symbol
		(lib_id "k410t-devboard:Net-Tie_2")
		(at 180.34 111.76 0)
		(mirror x)
		(unit 1)
		(exclude_from_sim no)
		(in_bom yes)
		(on_board yes)
		(dnp no)
		(fields_autoplaced yes)
		(property "Reference" "NT3"
			(at 180.34 113.03 0)
			(effects
				(font
					(size 1.27 1.27)
				)
				(hide yes)
			)
		)
		(property "Value" "Net-Tie_2"
			(at 201.93 109.22 0)
			(effects
				(font
					(size 1.27 1.27)
					(thickness 0.15)
				)
				(justify left bottom)
				(hide yes)
			)
		)
		(property "Footprint" "antmicro-footprints:NetTie-2_SMD_Pad0.127mm"
			(at 201.93 106.68 0)
			(effects
				(font
					(size 1.27 1.27)
					(thickness 0.15)
				)
				(justify left bottom)
				(hide yes)
			)
		)
		(property "Datasheet" ""
			(at 201.93 104.14 0)
			(effects
				(font
					(size 1.27 1.27)
					(thickness 0.15)
				)
				(justify left bottom)
				(hide yes)
			)
		)
		(property "Description" ""
			(at 180.34 111.76 0)
			(effects
				(font
					(size 1.27 1.27)
				)
			)
		)
		(property "MPN" ""
			(at 201.93 102.87 0)
			(effects
				(font
					(size 1.27 1.27)
				)
				(justify left)
				(hide yes)
			)
		)
		(property "Manufacturer" ""
			(at 201.93 100.33 0)
			(effects
				(font
					(size 1.27 1.27)
				)
				(justify left)
				(hide yes)
			)
		)
		(property "Author" "Antmicro"
			(at 201.93 96.52 0)
			(effects
				(font
					(size 1.27 1.27)
					(thickness 0.15)
				)
				(justify left bottom)
				(hide yes)
			)
		)
		(property "License" "Apache-2.0"
			(at 201.93 93.98 0)
			(effects
				(font
					(size 1.27 1.27)
					(thickness 0.15)
				)
				(justify left bottom)
				(hide yes)
			)
		)
		(pin "1"
		)
		(pin "2"
		)
		(instances
			(project "k410t-devboard"
				(path ""
					(reference "NT3")
					(unit 1)
				)
			)
		)
	)
	(symbol
		(lib_id "antmicroLEDIndicationDiscrete:LED_G_0603_KP-1608CGCK")
		(at 335.28 116.84 0)
		(mirror y)
		(unit 1)
		(exclude_from_sim no)
		(in_bom yes)
		(on_board yes)
		(dnp no)
		(fields_autoplaced yes)
		(property "Reference" "D2"
			(at 332.74 109.22 0)
			(effects
				(font
					(size 1.27 1.27)
				)
			)
		)
		(property "Value" "LED_G_0603_KP-1608CGCK"
			(at 331.47 123.19 0)
			(effects
				(font
					(size 1.27 1.27)
					(thickness 0.15)
				)
				(justify left bottom)
				(hide yes)
			)
		)
		(property "Footprint" "antmicro-footprints:LED_0603_1608Metric_G"
			(at 312.42 127 0)
			(effects
				(font
					(size 1.27 1.27)
					(thickness 0.15)
				)
				(justify left bottom)
				(hide yes)
			)
		)
		(property "Datasheet" "http://www.kingbright.com/attachments/file/psearch//000/00/00/KP-1608CGCK(Ver.23B).pdf"
			(at 312.42 129.54 0)
			(effects
				(font
					(size 1.27 1.27)
					(thickness 0.15)
				)
				(justify left bottom)
				(hide yes)
			)
		)
		(property "Description" ""
			(at 335.28 116.84 0)
			(effects
				(font
					(size 1.27 1.27)
				)
			)
		)
		(property "MPN" "KP-1608CGCK"
			(at 312.42 132.08 0)
			(effects
				(font
					(size 1.27 1.27)
					(thickness 0.15)
				)
				(justify left bottom)
				(hide yes)
			)
		)
		(property "Manufacturer" "Kingbright"
			(at 312.42 134.62 0)
			(effects
				(font
					(size 1.27 1.27)
					(thickness 0.15)
				)
				(justify left bottom)
				(hide yes)
			)
		)
		(property "Author" "Antmicro"
			(at 312.42 137.16 0)
			(effects
				(font
					(size 1.27 1.27)
					(thickness 0.15)
				)
				(justify left bottom)
				(hide yes)
			)
		)
		(property "License" "Apache-2.0"
			(at 312.42 139.7 0)
			(effects
				(font
					(size 1.27 1.27)
					(thickness 0.15)
				)
				(justify left bottom)
				(hide yes)
			)
		)
		(property "Color" "Green"
			(at 332.74 111.76 0)
			(effects
				(font
					(size 1.27 1.27)
				)
			)
		)
		(pin "1"
		)
		(pin "2"
		)
		(instances
			(project "k410t-devboard"
				(path ""
					(reference "D2")
					(unit 1)
				)
			)
		)
	)
	(symbol
		(lib_id "antmicropower:GND")
		(at 360.68 144.78 0)
		(unit 1)
		(exclude_from_sim no)
		(in_bom yes)
		(on_board yes)
		(dnp no)
		(fields_autoplaced yes)
		(property "Reference" "#PWR056"
			(at 360.68 151.13 0)
			(effects
				(font
					(size 1.27 1.27)
				)
				(hide yes)
			)
		)
		(property "Value" "GND"
			(at 360.68 149.225 0)
			(effects
				(font
					(size 1.27 1.27)
				)
			)
		)
		(property "Footprint" ""
			(at 369.57 152.4 0)
			(effects
				(font
					(size 1.27 1.27)
					(thickness 0.15)
				)
				(justify left bottom)
				(hide yes)
			)
		)
		(property "Datasheet" ""
			(at 369.57 157.48 0)
			(effects
				(font
					(size 1.27 1.27)
					(thickness 0.15)
				)
				(justify left bottom)
				(hide yes)
			)
		)
		(property "Description" ""
			(at 360.68 144.78 0)
			(effects
				(font
					(size 1.27 1.27)
				)
			)
		)
		(property "Author" "Antmicro"
			(at 369.57 152.4 0)
			(effects
				(font
					(size 1.27 1.27)
					(thickness 0.15)
				)
				(justify left bottom)
				(hide yes)
			)
		)
		(property "License" "Apache-2.0"
			(at 369.57 154.94 0)
			(effects
				(font
					(size 1.27 1.27)
					(thickness 0.15)
				)
				(justify left bottom)
				(hide yes)
			)
		)
		(pin "1"
		)
		(instances
			(project "k410t-devboard"
				(path ""
					(reference "#PWR056")
					(unit 1)
				)
			)
		)
	)
	(symbol
		(lib_id "antmicroResistors0402:R_10k_0402")
		(at 355.6 185.42 90)
		(unit 1)
		(exclude_from_sim no)
		(in_bom yes)
		(on_board yes)
		(dnp no)
		(property "Reference" "R11"
			(at 356.87 181.61 90)
			(effects
				(font
					(size 1.27 1.27)
				)
				(justify right)
			)
		)
		(property "Value" "R_10k_0402"
			(at 368.3 165.1 0)
			(effects
				(font
					(size 1.27 1.27)
					(thickness 0.15)
				)
				(justify left bottom)
				(hide yes)
			)
		)
		(property "Footprint" "antmicro-footprints:R_0402_1005Metric"
			(at 370.84 165.1 0)
			(effects
				(font
					(size 1.27 1.27)
					(thickness 0.15)
				)
				(justify left bottom)
				(hide yes)
			)
		)
		(property "Datasheet" "https://www.bourns.com/docs/product-datasheets/cr.pdf"
			(at 373.38 165.1 0)
			(effects
				(font
					(size 1.27 1.27)
					(thickness 0.15)
				)
				(justify left bottom)
				(hide yes)
			)
		)
		(property "Description" ""
			(at 355.6 185.42 0)
			(effects
				(font
					(size 1.27 1.27)
				)
			)
		)
		(property "Manufacturer" "Bourns"
			(at 378.46 165.1 0)
			(effects
				(font
					(size 1.27 1.27)
					(thickness 0.15)
				)
				(justify left bottom)
				(hide yes)
			)
		)
		(property "MPN" "CR0402-FX-1002GLF"
			(at 375.92 165.1 0)
			(effects
				(font
					(size 1.27 1.27)
					(thickness 0.15)
				)
				(justify left bottom)
				(hide yes)
			)
		)
		(property "Val" "10k"
			(at 356.87 184.15 90)
			(effects
				(font
					(size 1.27 1.27)
					(thickness 0.15)
				)
				(justify right)
			)
		)
		(property "License" "Apache-2.0"
			(at 381 165.1 0)
			(effects
				(font
					(size 1.27 1.27)
					(thickness 0.15)
				)
				(justify left bottom)
				(hide yes)
			)
		)
		(property "Author" "Antmicro"
			(at 383.54 165.1 0)
			(effects
				(font
					(size 1.27 1.27)
					(thickness 0.15)
				)
				(justify left bottom)
				(hide yes)
			)
		)
		(property "Tolerance" "1%"
			(at 365.76 165.1 0)
			(effects
				(font
					(size 1.27 1.27)
				)
				(justify left bottom)
				(hide yes)
			)
		)
		(pin "1"
		)
		(pin "2"
		)
		(instances
			(project "k410t-devboard"
				(path ""
					(reference "R11")
					(unit 1)
				)
			)
		)
	)
	(symbol
		(lib_id "antmicroCapacitorsmisc:C_100n_0201")
		(at 270.51 143.51 90)
		(unit 1)
		(exclude_from_sim no)
		(in_bom yes)
		(on_board yes)
		(dnp no)
		(property "Reference" "C266"
			(at 271.145 139.065 90)
			(effects
				(font
					(size 1.27 1.27)
				)
				(justify right)
			)
		)
		(property "Value" "C_100n_0201"
			(at 280.67 123.19 0)
			(effects
				(font
					(size 1.27 1.27)
					(thickness 0.15)
				)
				(justify left bottom)
				(hide yes)
			)
		)
		(property "Footprint" "antmicro-footprints:C_0201"
			(at 283.21 123.19 0)
			(effects
				(font
					(size 1.27 1.27)
					(thickness 0.15)
				)
				(justify left bottom)
				(hide yes)
			)
		)
		(property "Datasheet" "https://www.yageo.com/en/Chart/Download/pdf/CC0201KRX6S5BB104"
			(at 285.75 123.19 0)
			(effects
				(font
					(size 1.27 1.27)
					(thickness 0.15)
				)
				(justify left bottom)
				(hide yes)
			)
		)
		(property "Description" ""
			(at 270.51 143.51 0)
			(effects
				(font
					(size 1.27 1.27)
				)
			)
		)
		(property "Manufacturer" "YAGEO"
			(at 290.83 123.19 0)
			(effects
				(font
					(size 1.27 1.27)
					(thickness 0.15)
				)
				(justify left bottom)
				(hide yes)
			)
		)
		(property "MPN" "CC0201KRX6S5BB104"
			(at 288.29 123.19 0)
			(effects
				(font
					(size 1.27 1.27)
					(thickness 0.15)
				)
				(justify left bottom)
				(hide yes)
			)
		)
		(property "Val" "100n"
			(at 271.145 142.875 90)
			(effects
				(font
					(size 1.27 1.27)
					(thickness 0.15)
				)
				(justify right)
			)
		)
		(property "License" "Apache-2.0"
			(at 293.37 123.19 0)
			(effects
				(font
					(size 1.27 1.27)
					(thickness 0.15)
				)
				(justify left bottom)
				(hide yes)
			)
		)
		(property "Author" "Antmicro"
			(at 295.91 123.19 0)
			(effects
				(font
					(size 1.27 1.27)
					(thickness 0.15)
				)
				(justify left bottom)
				(hide yes)
			)
		)
		(property "Voltage" ""
			(at 298.45 123.19 0)
			(effects
				(font
					(size 1.27 1.27)
				)
				(justify left bottom)
				(hide yes)
			)
		)
		(property "Dielectric" ""
			(at 300.99 123.19 0)
			(effects
				(font
					(size 1.27 1.27)
				)
				(justify left bottom)
				(hide yes)
			)
		)
		(pin "1"
		)
		(pin "2"
		)
		(instances
			(project "k410t-devboard"
				(path ""
					(reference "C266")
					(unit 1)
				)
			)
		)
	)
	(symbol
		(lib_id "antmicroResistors0402:R_10k_0402")
		(at 125.73 127 270)
		(mirror x)
		(unit 1)
		(exclude_from_sim no)
		(in_bom no)
		(on_board yes)
		(dnp yes)
		(property "Reference" "R4"
			(at 127 123.19 90)
			(effects
				(font
					(size 1.27 1.27)
				)
				(justify left)
			)
		)
		(property "Value" "R_10k_0402"
			(at 113.03 106.68 0)
			(effects
				(font
					(size 1.27 1.27)
					(thickness 0.15)
				)
				(justify left bottom)
				(hide yes)
			)
		)
		(property "Footprint" "antmicro-footprints:R_0402_1005Metric"
			(at 110.49 106.68 0)
			(effects
				(font
					(size 1.27 1.27)
					(thickness 0.15)
				)
				(justify left bottom)
				(hide yes)
			)
		)
		(property "Datasheet" "https://www.bourns.com/docs/product-datasheets/cr.pdf"
			(at 107.95 106.68 0)
			(effects
				(font
					(size 1.27 1.27)
					(thickness 0.15)
				)
				(justify left bottom)
				(hide yes)
			)
		)
		(property "Description" ""
			(at 125.73 127 0)
			(effects
				(font
					(size 1.27 1.27)
				)
			)
		)
		(property "Manufacturer" "Bourns"
			(at 102.87 106.68 0)
			(effects
				(font
					(size 1.27 1.27)
					(thickness 0.15)
				)
				(justify left bottom)
				(hide yes)
			)
		)
		(property "MPN" "CR0402-FX-1002GLF"
			(at 105.41 106.68 0)
			(effects
				(font
					(size 1.27 1.27)
					(thickness 0.15)
				)
				(justify left bottom)
				(hide yes)
			)
		)
		(property "Val" "10k"
			(at 127 125.73 90)
			(effects
				(font
					(size 1.27 1.27)
					(thickness 0.15)
				)
				(justify left)
			)
		)
		(property "DNP" "DNP"
			(at 125.73 126.365 0)
			(effects
				(font
					(size 1.27 1.27)
				)
				(justify left)
			)
		)
		(property "License" "Apache-2.0"
			(at 100.33 106.68 0)
			(effects
				(font
					(size 1.27 1.27)
					(thickness 0.15)
				)
				(justify left bottom)
				(hide yes)
			)
		)
		(property "Author" "Antmicro"
			(at 97.79 106.68 0)
			(effects
				(font
					(size 1.27 1.27)
					(thickness 0.15)
				)
				(justify left bottom)
				(hide yes)
			)
		)
		(property "Tolerance" "1%"
			(at 115.57 106.68 0)
			(effects
				(font
					(size 1.27 1.27)
				)
				(justify left bottom)
				(hide yes)
			)
		)
		(pin "1"
		)
		(pin "2"
		)
		(instances
			(project "k410t-devboard"
				(path ""
					(reference "R4")
					(unit 1)
				)
			)
		)
	)
	(symbol
		(lib_id "antmicropower:+3.3V")
		(at 55.88 220.98 0)
		(unit 1)
		(exclude_from_sim no)
		(in_bom yes)
		(on_board yes)
		(dnp no)
		(fields_autoplaced yes)
		(property "Reference" "#PWR043"
			(at 55.88 224.79 0)
			(effects
				(font
					(size 1.27 1.27)
				)
				(hide yes)
			)
		)
		(property "Value" "+3V3"
			(at 55.88 217.424 0)
			(effects
				(font
					(size 1.27 1.27)
				)
			)
		)
		(property "Footprint" ""
			(at 55.88 220.98 0)
			(effects
				(font
					(size 1.27 1.27)
				)
				(hide yes)
			)
		)
		(property "Datasheet" ""
			(at 55.88 220.98 0)
			(effects
				(font
					(size 1.27 1.27)
				)
				(hide yes)
			)
		)
		(property "Description" ""
			(at 55.88 220.98 0)
			(effects
				(font
					(size 1.27 1.27)
				)
			)
		)
		(pin "1"
		)
		(instances
			(project "k410t-devboard"
				(path ""
					(reference "#PWR043")
					(unit 1)
				)
			)
		)
	)
	(symbol
		(lib_id "antmicropower:GND")
		(at 361.95 97.79 0)
		(unit 1)
		(exclude_from_sim no)
		(in_bom yes)
		(on_board yes)
		(dnp no)
		(property "Reference" "#PWR054"
			(at 361.95 104.14 0)
			(effects
				(font
					(size 1.27 1.27)
				)
				(hide yes)
			)
		)
		(property "Value" "GND"
			(at 361.95 101.6 0)
			(effects
				(font
					(size 1.27 1.27)
				)
			)
		)
		(property "Footprint" ""
			(at 370.84 105.41 0)
			(effects
				(font
					(size 1.27 1.27)
					(thickness 0.15)
				)
				(justify left bottom)
				(hide yes)
			)
		)
		(property "Datasheet" ""
			(at 370.84 110.49 0)
			(effects
				(font
					(size 1.27 1.27)
					(thickness 0.15)
				)
				(justify left bottom)
				(hide yes)
			)
		)
		(property "Description" ""
			(at 361.95 97.79 0)
			(effects
				(font
					(size 1.27 1.27)
				)
			)
		)
		(property "Author" "Antmicro"
			(at 370.84 105.41 0)
			(effects
				(font
					(size 1.27 1.27)
					(thickness 0.15)
				)
				(justify left bottom)
				(hide yes)
			)
		)
		(property "License" "Apache-2.0"
			(at 370.84 107.95 0)
			(effects
				(font
					(size 1.27 1.27)
					(thickness 0.15)
				)
				(justify left bottom)
				(hide yes)
			)
		)
		(pin "1"
		)
		(instances
			(project "k410t-devboard"
				(path ""
					(reference "#PWR054")
					(unit 1)
				)
			)
		)
	)
	(symbol
		(lib_id "antmicroTemperatureSensorsAnalogandDigitalOutput:MAX1617AMEE+T")
		(at 316.23 173.99 0)
		(unit 1)
		(exclude_from_sim no)
		(in_bom yes)
		(on_board yes)
		(dnp no)
		(fields_autoplaced yes)
		(property "Reference" "U3"
			(at 328.5841 171.45 0)
			(effects
				(font
					(size 1.27 1.27)
				)
				(justify left)
			)
		)
		(property "Value" "MAX1617AMEE+T"
			(at 328.5841 173.99 0)
			(effects
				(font
					(size 1.27 1.27)
					(thickness 0.15)
				)
				(justify left)
			)
		)
		(property "Footprint" "antmicro-footprints:QSOP-16_3.9x4.9mm_P0.635mm"
			(at 351.79 186.69 0)
			(effects
				(font
					(size 1.27 1.27)
					(thickness 0.15)
				)
				(justify left bottom)
				(hide yes)
			)
		)
		(property "Datasheet" "https://www.analog.com/media/en/technical-documentation/data-sheets/MAX1617.pdf"
			(at 351.79 189.23 0)
			(effects
				(font
					(size 1.27 1.27)
					(thickness 0.15)
				)
				(justify left bottom)
				(hide yes)
			)
		)
		(property "Description" ""
			(at 316.23 173.99 0)
			(effects
				(font
					(size 1.27 1.27)
				)
			)
		)
		(property "MPN" "MAX1617AMEE+T"
			(at 351.79 191.77 0)
			(effects
				(font
					(size 1.27 1.27)
					(thickness 0.15)
				)
				(justify left bottom)
				(hide yes)
			)
		)
		(property "Manufacturer" "Maxim Integrated Products"
			(at 351.79 194.31 0)
			(effects
				(font
					(size 1.27 1.27)
					(thickness 0.15)
				)
				(justify left bottom)
				(hide yes)
			)
		)
		(property "Author" "Antmicro"
			(at 351.79 196.85 0)
			(effects
				(font
					(size 1.27 1.27)
					(thickness 0.15)
				)
				(justify left bottom)
				(hide yes)
			)
		)
		(property "License" "Apache-2.0"
			(at 351.79 199.39 0)
			(effects
				(font
					(size 1.27 1.27)
					(thickness 0.15)
				)
				(justify left bottom)
				(hide yes)
			)
		)
		(pin "1"
		)
		(pin "10"
		)
		(pin "11"
		)
		(pin "12"
		)
		(pin "13"
		)
		(pin "14"
		)
		(pin "15"
		)
		(pin "16"
		)
		(pin "2"
		)
		(pin "3"
		)
		(pin "4"
		)
		(pin "5"
		)
		(pin "6"
		)
		(pin "7"
		)
		(pin "8"
		)
		(pin "9"
		)
		(instances
			(project "k410t-devboard"
				(path ""
					(reference "U3")
					(unit 1)
				)
			)
		)
	)
	(symbol
		(lib_id "antmicroTransistorsFETsMOSFETsSingle:BSS138PW")
		(at 355.6 102.87 90)
		(unit 1)
		(exclude_from_sim no)
		(in_bom yes)
		(on_board yes)
		(dnp no)
		(fields_autoplaced yes)
		(property "Reference" "Q1"
			(at 353.06 88.265 90)
			(effects
				(font
					(size 1.27 1.27)
				)
			)
		)
		(property "Value" "BSS138PW"
			(at 353.06 90.805 90)
			(effects
				(font
					(size 1.27 1.27)
					(thickness 0.15)
				)
			)
		)
		(property "Footprint" "antmicro-footprints:SC70-3"
			(at 367.03 80.01 0)
			(effects
				(font
					(size 1.27 1.27)
					(thickness 0.15)
				)
				(justify left bottom)
				(hide yes)
			)
		)
		(property "Datasheet" "https://assets.nexperia.com/documents/data-sheet/BSS138PW.pdf"
			(at 369.57 80.01 0)
			(effects
				(font
					(size 1.27 1.27)
					(thickness 0.15)
				)
				(justify left bottom)
				(hide yes)
			)
		)
		(property "Description" ""
			(at 355.6 102.87 0)
			(effects
				(font
					(size 1.27 1.27)
				)
			)
		)
		(property "MPN" "BSS138PW"
			(at 372.11 80.01 0)
			(effects
				(font
					(size 1.27 1.27)
					(thickness 0.15)
				)
				(justify left bottom)
				(hide yes)
			)
		)
		(property "Manufacturer" "Nexperia"
			(at 374.65 80.01 0)
			(effects
				(font
					(size 1.27 1.27)
					(thickness 0.15)
				)
				(justify left bottom)
				(hide yes)
			)
		)
		(property "Author" "Antmicro"
			(at 377.19 80.01 0)
			(effects
				(font
					(size 1.27 1.27)
					(thickness 0.15)
				)
				(justify left bottom)
				(hide yes)
			)
		)
		(property "License" "Apache-2.0"
			(at 379.73 80.01 0)
			(effects
				(font
					(size 1.27 1.27)
					(thickness 0.15)
				)
				(justify left bottom)
				(hide yes)
			)
		)
		(pin "1"
		)
		(pin "2"
		)
		(pin "3"
		)
		(instances
			(project "k410t-devboard"
				(path ""
					(reference "Q1")
					(unit 1)
				)
			)
		)
	)
	(symbol
		(lib_id "k410t-devboard:Net-Tie_2")
		(at 180.34 114.3 0)
		(mirror x)
		(unit 1)
		(exclude_from_sim no)
		(in_bom yes)
		(on_board yes)
		(dnp no)
		(fields_autoplaced yes)
		(property "Reference" "NT19"
			(at 180.34 115.57 0)
			(effects
				(font
					(size 1.27 1.27)
				)
				(hide yes)
			)
		)
		(property "Value" "Net-Tie_2"
			(at 201.93 111.76 0)
			(effects
				(font
					(size 1.27 1.27)
					(thickness 0.15)
				)
				(justify left bottom)
				(hide yes)
			)
		)
		(property "Footprint" "antmicro-footprints:NetTie-2_SMD_Pad0.127mm"
			(at 201.93 109.22 0)
			(effects
				(font
					(size 1.27 1.27)
					(thickness 0.15)
				)
				(justify left bottom)
				(hide yes)
			)
		)
		(property "Datasheet" ""
			(at 201.93 106.68 0)
			(effects
				(font
					(size 1.27 1.27)
					(thickness 0.15)
				)
				(justify left bottom)
				(hide yes)
			)
		)
		(property "Description" ""
			(at 180.34 114.3 0)
			(effects
				(font
					(size 1.27 1.27)
				)
			)
		)
		(property "MPN" ""
			(at 201.93 105.41 0)
			(effects
				(font
					(size 1.27 1.27)
				)
				(justify left)
				(hide yes)
			)
		)
		(property "Manufacturer" ""
			(at 201.93 102.87 0)
			(effects
				(font
					(size 1.27 1.27)
				)
				(justify left)
				(hide yes)
			)
		)
		(property "Author" "Antmicro"
			(at 201.93 99.06 0)
			(effects
				(font
					(size 1.27 1.27)
					(thickness 0.15)
				)
				(justify left bottom)
				(hide yes)
			)
		)
		(property "License" "Apache-2.0"
			(at 201.93 96.52 0)
			(effects
				(font
					(size 1.27 1.27)
					(thickness 0.15)
				)
				(justify left bottom)
				(hide yes)
			)
		)
		(pin "1"
		)
		(pin "2"
		)
		(instances
			(project "k410t-devboard"
				(path ""
					(reference "NT19")
					(unit 1)
				)
			)
		)
	)
	(symbol
		(lib_id "antmicropower:GND")
		(at 326.39 203.2 0)
		(unit 1)
		(exclude_from_sim no)
		(in_bom yes)
		(on_board yes)
		(dnp no)
		(property "Reference" "#PWR051"
			(at 326.39 209.55 0)
			(effects
				(font
					(size 1.27 1.27)
				)
				(hide yes)
			)
		)
		(property "Value" "GND"
			(at 326.39 207.01 0)
			(effects
				(font
					(size 1.27 1.27)
				)
			)
		)
		(property "Footprint" ""
			(at 335.28 210.82 0)
			(effects
				(font
					(size 1.27 1.27)
					(thickness 0.15)
				)
				(justify left bottom)
				(hide yes)
			)
		)
		(property "Datasheet" ""
			(at 335.28 215.9 0)
			(effects
				(font
					(size 1.27 1.27)
					(thickness 0.15)
				)
				(justify left bottom)
				(hide yes)
			)
		)
		(property "Description" ""
			(at 326.39 203.2 0)
			(effects
				(font
					(size 1.27 1.27)
				)
			)
		)
		(property "Author" "Antmicro"
			(at 335.28 210.82 0)
			(effects
				(font
					(size 1.27 1.27)
					(thickness 0.15)
				)
				(justify left bottom)
				(hide yes)
			)
		)
		(property "License" "Apache-2.0"
			(at 335.28 213.36 0)
			(effects
				(font
					(size 1.27 1.27)
					(thickness 0.15)
				)
				(justify left bottom)
				(hide yes)
			)
		)
		(pin "1"
		)
		(instances
			(project "k410t-devboard"
				(path ""
					(reference "#PWR051")
					(unit 1)
				)
			)
		)
	)
	(symbol
		(lib_id "antmicropower:GND")
		(at 38.1 248.92 0)
		(unit 1)
		(exclude_from_sim no)
		(in_bom yes)
		(on_board yes)
		(dnp no)
		(property "Reference" "#PWR044"
			(at 38.1 255.27 0)
			(effects
				(font
					(size 1.27 1.27)
				)
				(hide yes)
			)
		)
		(property "Value" "GND"
			(at 38.1 252.73 0)
			(effects
				(font
					(size 1.27 1.27)
				)
			)
		)
		(property "Footprint" ""
			(at 46.99 256.54 0)
			(effects
				(font
					(size 1.27 1.27)
					(thickness 0.15)
				)
				(justify left bottom)
				(hide yes)
			)
		)
		(property "Datasheet" ""
			(at 46.99 261.62 0)
			(effects
				(font
					(size 1.27 1.27)
					(thickness 0.15)
				)
				(justify left bottom)
				(hide yes)
			)
		)
		(property "Description" ""
			(at 38.1 248.92 0)
			(effects
				(font
					(size 1.27 1.27)
				)
			)
		)
		(property "Author" "Antmicro"
			(at 46.99 256.54 0)
			(effects
				(font
					(size 1.27 1.27)
					(thickness 0.15)
				)
				(justify left bottom)
				(hide yes)
			)
		)
		(property "License" "Apache-2.0"
			(at 46.99 259.08 0)
			(effects
				(font
					(size 1.27 1.27)
					(thickness 0.15)
				)
				(justify left bottom)
				(hide yes)
			)
		)
		(pin "1"
		)
		(instances
			(project "k410t-devboard"
				(path ""
					(reference "#PWR044")
					(unit 1)
				)
			)
		)
	)
	(symbol
		(lib_id "antmicroResistors0402:R_10k_0402")
		(at 259.08 120.65 90)
		(unit 1)
		(exclude_from_sim no)
		(in_bom yes)
		(on_board yes)
		(dnp no)
		(property "Reference" "R7"
			(at 260.35 116.84 90)
			(effects
				(font
					(size 1.27 1.27)
				)
				(justify right)
			)
		)
		(property "Value" "R_10k_0402"
			(at 271.78 100.33 0)
			(effects
				(font
					(size 1.27 1.27)
					(thickness 0.15)
				)
				(justify left bottom)
				(hide yes)
			)
		)
		(property "Footprint" "antmicro-footprints:R_0402_1005Metric"
			(at 274.32 100.33 0)
			(effects
				(font
					(size 1.27 1.27)
					(thickness 0.15)
				)
				(justify left bottom)
				(hide yes)
			)
		)
		(property "Datasheet" "https://www.bourns.com/docs/product-datasheets/cr.pdf"
			(at 276.86 100.33 0)
			(effects
				(font
					(size 1.27 1.27)
					(thickness 0.15)
				)
				(justify left bottom)
				(hide yes)
			)
		)
		(property "Description" ""
			(at 259.08 120.65 0)
			(effects
				(font
					(size 1.27 1.27)
				)
			)
		)
		(property "Manufacturer" "Bourns"
			(at 281.94 100.33 0)
			(effects
				(font
					(size 1.27 1.27)
					(thickness 0.15)
				)
				(justify left bottom)
				(hide yes)
			)
		)
		(property "MPN" "CR0402-FX-1002GLF"
			(at 279.4 100.33 0)
			(effects
				(font
					(size 1.27 1.27)
					(thickness 0.15)
				)
				(justify left bottom)
				(hide yes)
			)
		)
		(property "Val" "10k"
			(at 260.35 119.38 90)
			(effects
				(font
					(size 1.27 1.27)
					(thickness 0.15)
				)
				(justify right)
			)
		)
		(property "License" "Apache-2.0"
			(at 284.48 100.33 0)
			(effects
				(font
					(size 1.27 1.27)
					(thickness 0.15)
				)
				(justify left bottom)
				(hide yes)
			)
		)
		(property "Author" "Antmicro"
			(at 287.02 100.33 0)
			(effects
				(font
					(size 1.27 1.27)
					(thickness 0.15)
				)
				(justify left bottom)
				(hide yes)
			)
		)
		(property "Tolerance" "1%"
			(at 269.24 100.33 0)
			(effects
				(font
					(size 1.27 1.27)
				)
				(justify left bottom)
				(hide yes)
			)
		)
		(pin "1"
		)
		(pin "2"
		)
		(instances
			(project "k410t-devboard"
				(path ""
					(reference "R7")
					(unit 1)
				)
			)
		)
	)
	(symbol
		(lib_id "antmicropower:+3.3V")
		(at 326.39 92.71 0)
		(unit 1)
		(exclude_from_sim no)
		(in_bom yes)
		(on_board yes)
		(dnp no)
		(fields_autoplaced yes)
		(property "Reference" "#PWR052"
			(at 326.39 96.52 0)
			(effects
				(font
					(size 1.27 1.27)
				)
				(hide yes)
			)
		)
		(property "Value" "+3V3"
			(at 326.39 89.154 0)
			(effects
				(font
					(size 1.27 1.27)
				)
			)
		)
		(property "Footprint" ""
			(at 326.39 92.71 0)
			(effects
				(font
					(size 1.27 1.27)
				)
				(hide yes)
			)
		)
		(property "Datasheet" ""
			(at 326.39 92.71 0)
			(effects
				(font
					(size 1.27 1.27)
				)
				(hide yes)
			)
		)
		(property "Description" ""
			(at 326.39 92.71 0)
			(effects
				(font
					(size 1.27 1.27)
				)
			)
		)
		(pin "1"
		)
		(instances
			(project "k410t-devboard"
				(path ""
					(reference "#PWR052")
					(unit 1)
				)
			)
		)
	)
	(symbol
		(lib_id "antmicroPushbuttonSwitches:SW_KMR211NGLFS_SMD")
		(at 349.25 139.7 0)
		(unit 1)
		(exclude_from_sim no)
		(in_bom yes)
		(on_board yes)
		(dnp no)
		(fields_autoplaced yes)
		(property "Reference" "S1"
			(at 354.33 132.08 0)
			(effects
				(font
					(size 1.27 1.27)
				)
			)
		)
		(property "Value" "SW_KMR211NGLFS_SMD"
			(at 354.33 134.62 0)
			(effects
				(font
					(size 1.27 1.27)
					(thickness 0.15)
				)
			)
		)
		(property "Footprint" "antmicro-footprints:SW_KMR211NGLFS_SMD"
			(at 374.65 147.32 0)
			(effects
				(font
					(size 1.27 1.27)
					(thickness 0.15)
				)
				(justify left bottom)
				(hide yes)
			)
		)
		(property "Datasheet" "http://www.farnell.com/datasheets/2631211.pdf"
			(at 374.65 149.86 0)
			(effects
				(font
					(size 1.27 1.27)
					(thickness 0.15)
				)
				(justify left bottom)
				(hide yes)
			)
		)
		(property "Description" ""
			(at 349.25 139.7 0)
			(effects
				(font
					(size 1.27 1.27)
				)
			)
		)
		(property "MPN" "KMR211NGLFS"
			(at 374.65 152.4 0)
			(effects
				(font
					(size 1.27 1.27)
					(thickness 0.15)
				)
				(justify left bottom)
				(hide yes)
			)
		)
		(property "Manufacturer" "C&K"
			(at 374.65 154.94 0)
			(effects
				(font
					(size 1.27 1.27)
					(thickness 0.15)
				)
				(justify left bottom)
				(hide yes)
			)
		)
		(property "Author" "Antmicro"
			(at 374.65 157.48 0)
			(effects
				(font
					(size 1.27 1.27)
					(thickness 0.15)
				)
				(justify left bottom)
				(hide yes)
			)
		)
		(property "License" "Apache-2.0"
			(at 374.65 160.02 0)
			(effects
				(font
					(size 1.27 1.27)
					(thickness 0.15)
				)
				(justify left bottom)
				(hide yes)
			)
		)
		(pin "1"
		)
		(pin "2"
		)
		(pin "3"
		)
		(pin "4"
		)
		(instances
			(project "k410t-devboard"
				(path ""
					(reference "S1")
					(unit 1)
				)
			)
		)
	)
	(symbol
		(lib_id "antmicroSlideSwitches:CVS-03B")
		(at 99.06 130.81 0)
		(mirror y)
		(unit 1)
		(exclude_from_sim no)
		(in_bom yes)
		(on_board yes)
		(dnp no)
		(fields_autoplaced yes)
		(property "Reference" "SW1"
			(at 92.71 123.19 0)
			(effects
				(font
					(size 1.27 1.27)
				)
			)
		)
		(property "Value" "CVS-03B"
			(at 99.06 146.685 0)
			(effects
				(font
					(size 1.27 1.27)
				)
				(hide yes)
			)
		)
		(property "Footprint" "antmicro-footprints:SW_DIP_SPSTx03_Slide_Copal_CVS-03xB_W5.9mm_P1mm"
			(at 99.06 142.24 0)
			(effects
				(font
					(size 1.27 1.27)
				)
				(hide yes)
			)
		)
		(property "Datasheet" "https://www.mouser.com/datasheet/2/972/cvs-1827291.pdf"
			(at 99.06 144.78 0)
			(effects
				(font
					(size 1.27 1.27)
				)
				(hide yes)
			)
		)
		(property "Description" ""
			(at 99.06 130.81 0)
			(effects
				(font
					(size 1.27 1.27)
				)
			)
		)
		(property "MPN" "CVS-03B"
			(at 92.71 125.73 0)
			(effects
				(font
					(size 1.27 1.27)
				)
			)
		)
		(property "Manufacturer" "Nidec Components"
			(at 99.06 139.7 0)
			(effects
				(font
					(size 1.27 1.27)
				)
				(hide yes)
			)
		)
		(property "Author" "Antmicro"
			(at 72.39 148.59 0)
			(effects
				(font
					(size 1.27 1.27)
					(thickness 0.15)
				)
				(justify left bottom)
				(hide yes)
			)
		)
		(property "License" "Apache-2.0"
			(at 72.39 151.13 0)
			(effects
				(font
					(size 1.27 1.27)
					(thickness 0.15)
				)
				(justify left bottom)
				(hide yes)
			)
		)
		(pin "1"
		)
		(pin "2"
		)
		(pin "3"
		)
		(pin "4"
		)
		(pin "5"
		)
		(pin "6"
		)
		(pin "7"
		)
		(instances
			(project "k410t-devboard"
				(path ""
					(reference "SW1")
					(unit 1)
				)
			)
		)
	)
	(symbol
		(lib_id "antmicropower:+3.3V")
		(at 163.83 66.04 0)
		(unit 1)
		(exclude_from_sim no)
		(in_bom yes)
		(on_board yes)
		(dnp no)
		(fields_autoplaced yes)
		(property "Reference" "#PWR03"
			(at 163.83 69.85 0)
			(effects
				(font
					(size 1.27 1.27)
				)
				(hide yes)
			)
		)
		(property "Value" "+3V3"
			(at 163.83 62.484 0)
			(effects
				(font
					(size 1.27 1.27)
				)
			)
		)
		(property "Footprint" ""
			(at 163.83 66.04 0)
			(effects
				(font
					(size 1.27 1.27)
				)
				(hide yes)
			)
		)
		(property "Datasheet" ""
			(at 163.83 66.04 0)
			(effects
				(font
					(size 1.27 1.27)
				)
				(hide yes)
			)
		)
		(property "Description" ""
			(at 163.83 66.04 0)
			(effects
				(font
					(size 1.27 1.27)
				)
			)
		)
		(pin "1"
		)
		(instances
			(project "k410t-devboard"
				(path ""
					(reference "#PWR03")
					(unit 1)
				)
			)
		)
	)
	(symbol
		(lib_id "antmicroResistors0402:R_10k_0402")
		(at 312.42 172.72 90)
		(unit 1)
		(exclude_from_sim no)
		(in_bom yes)
		(on_board yes)
		(dnp no)
		(property "Reference" "R8"
			(at 313.69 168.91 90)
			(effects
				(font
					(size 1.27 1.27)
				)
				(justify right)
			)
		)
		(property "Value" "R_10k_0402"
			(at 325.12 152.4 0)
			(effects
				(font
					(size 1.27 1.27)
					(thickness 0.15)
				)
				(justify left bottom)
				(hide yes)
			)
		)
		(property "Footprint" "antmicro-footprints:R_0402_1005Metric"
			(at 327.66 152.4 0)
			(effects
				(font
					(size 1.27 1.27)
					(thickness 0.15)
				)
				(justify left bottom)
				(hide yes)
			)
		)
		(property "Datasheet" "https://www.bourns.com/docs/product-datasheets/cr.pdf"
			(at 330.2 152.4 0)
			(effects
				(font
					(size 1.27 1.27)
					(thickness 0.15)
				)
				(justify left bottom)
				(hide yes)
			)
		)
		(property "Description" ""
			(at 312.42 172.72 0)
			(effects
				(font
					(size 1.27 1.27)
				)
			)
		)
		(property "Manufacturer" "Bourns"
			(at 335.28 152.4 0)
			(effects
				(font
					(size 1.27 1.27)
					(thickness 0.15)
				)
				(justify left bottom)
				(hide yes)
			)
		)
		(property "MPN" "CR0402-FX-1002GLF"
			(at 332.74 152.4 0)
			(effects
				(font
					(size 1.27 1.27)
					(thickness 0.15)
				)
				(justify left bottom)
				(hide yes)
			)
		)
		(property "Val" "10k"
			(at 313.69 171.45 90)
			(effects
				(font
					(size 1.27 1.27)
					(thickness 0.15)
				)
				(justify right)
			)
		)
		(property "License" "Apache-2.0"
			(at 337.82 152.4 0)
			(effects
				(font
					(size 1.27 1.27)
					(thickness 0.15)
				)
				(justify left bottom)
				(hide yes)
			)
		)
		(property "Author" "Antmicro"
			(at 340.36 152.4 0)
			(effects
				(font
					(size 1.27 1.27)
					(thickness 0.15)
				)
				(justify left bottom)
				(hide yes)
			)
		)
		(property "Tolerance" "1%"
			(at 322.58 152.4 0)
			(effects
				(font
					(size 1.27 1.27)
				)
				(justify left bottom)
				(hide yes)
			)
		)
		(pin "1"
		)
		(pin "2"
		)
		(instances
			(project "k410t-devboard"
				(path ""
					(reference "R8")
					(unit 1)
				)
			)
		)
	)
	(symbol
		(lib_id "antmicroCapacitors0402:C_2n2_0402")
		(at 299.72 187.96 90)
		(unit 1)
		(exclude_from_sim no)
		(in_bom yes)
		(on_board yes)
		(dnp no)
		(property "Reference" "C165"
			(at 300.355 183.515 90)
			(effects
				(font
					(size 1.27 1.27)
				)
				(justify right)
			)
		)
		(property "Value" "C_2n2_0402"
			(at 309.88 167.64 0)
			(effects
				(font
					(size 1.27 1.27)
					(thickness 0.15)
				)
				(justify left bottom)
				(hide yes)
			)
		)
		(property "Footprint" "antmicro-footprints:C_0402_1005Metric"
			(at 312.42 167.64 0)
			(effects
				(font
					(size 1.27 1.27)
					(thickness 0.15)
				)
				(justify left bottom)
				(hide yes)
			)
		)
		(property "Datasheet" "https://www.kemet.com/en/us/capacitors/product/C0402C222J5RACTU.html"
			(at 314.96 167.64 0)
			(effects
				(font
					(size 1.27 1.27)
					(thickness 0.15)
				)
				(justify left bottom)
				(hide yes)
			)
		)
		(property "Description" ""
			(at 299.72 187.96 0)
			(effects
				(font
					(size 1.27 1.27)
				)
			)
		)
		(property "Manufacturer" "KEMET"
			(at 320.04 167.64 0)
			(effects
				(font
					(size 1.27 1.27)
					(thickness 0.15)
				)
				(justify left bottom)
				(hide yes)
			)
		)
		(property "MPN" "C0402C222J5RACTU"
			(at 317.5 167.64 0)
			(effects
				(font
					(size 1.27 1.27)
					(thickness 0.15)
				)
				(justify left bottom)
				(hide yes)
			)
		)
		(property "Val" "2n2"
			(at 300.355 187.325 90)
			(effects
				(font
					(size 1.27 1.27)
					(thickness 0.15)
				)
				(justify right)
			)
		)
		(property "License" "Apache-2.0"
			(at 322.58 167.64 0)
			(effects
				(font
					(size 1.27 1.27)
					(thickness 0.15)
				)
				(justify left bottom)
				(hide yes)
			)
		)
		(property "Author" "Antmicro"
			(at 325.12 167.64 0)
			(effects
				(font
					(size 1.27 1.27)
					(thickness 0.15)
				)
				(justify left bottom)
				(hide yes)
			)
		)
		(property "Voltage" ""
			(at 327.66 167.64 0)
			(effects
				(font
					(size 1.27 1.27)
				)
				(justify left bottom)
				(hide yes)
			)
		)
		(property "Dielectric" ""
			(at 330.2 167.64 0)
			(effects
				(font
					(size 1.27 1.27)
				)
				(justify left bottom)
				(hide yes)
			)
		)
		(pin "1"
		)
		(pin "2"
		)
		(instances
			(project "k410t-devboard"
				(path ""
					(reference "C165")
					(unit 1)
				)
			)
		)
	)
	(symbol
		(lib_id "antmicropower:GND")
		(at 361.95 119.38 0)
		(unit 1)
		(exclude_from_sim no)
		(in_bom yes)
		(on_board yes)
		(dnp no)
		(property "Reference" "#PWR055"
			(at 361.95 125.73 0)
			(effects
				(font
					(size 1.27 1.27)
				)
				(hide yes)
			)
		)
		(property "Value" "GND"
			(at 361.95 123.19 0)
			(effects
				(font
					(size 1.27 1.27)
				)
			)
		)
		(property "Footprint" ""
			(at 370.84 127 0)
			(effects
				(font
					(size 1.27 1.27)
					(thickness 0.15)
				)
				(justify left bottom)
				(hide yes)
			)
		)
		(property "Datasheet" ""
			(at 370.84 132.08 0)
			(effects
				(font
					(size 1.27 1.27)
					(thickness 0.15)
				)
				(justify left bottom)
				(hide yes)
			)
		)
		(property "Description" ""
			(at 361.95 119.38 0)
			(effects
				(font
					(size 1.27 1.27)
				)
			)
		)
		(property "Author" "Antmicro"
			(at 370.84 127 0)
			(effects
				(font
					(size 1.27 1.27)
					(thickness 0.15)
				)
				(justify left bottom)
				(hide yes)
			)
		)
		(property "License" "Apache-2.0"
			(at 370.84 129.54 0)
			(effects
				(font
					(size 1.27 1.27)
					(thickness 0.15)
				)
				(justify left bottom)
				(hide yes)
			)
		)
		(pin "1"
		)
		(instances
			(project "k410t-devboard"
				(path ""
					(reference "#PWR055")
					(unit 1)
				)
			)
		)
	)
	(symbol
		(lib_id "antmicroFPGAChips:XC7K410T-2FFG900I")
		(at 200.66 124.46 0)
		(unit 9)
		(exclude_from_sim no)
		(in_bom yes)
		(on_board yes)
		(dnp no)
		(fields_autoplaced yes)
		(property "Reference" "U1"
			(at 217.17 116.84 0)
			(effects
				(font
					(size 1.27 1.27)
					(thickness 0.15)
				)
			)
		)
		(property "Value" "XC7K410T-2FFG900I"
			(at 217.17 119.38 0)
			(effects
				(font
					(size 1.27 1.27)
					(thickness 0.15)
				)
			)
		)
		(property "Footprint" "antmicro-footprints:BGA-900_31x31mm_Layout30x30_P1x1mm_FFG900"
			(at 200.66 97.79 0)
			(effects
				(font
					(size 1.27 1.27)
					(thickness 0.15)
				)
				(justify left bottom)
				(hide yes)
			)
		)
		(property "Datasheet" "https://eu.mouser.com/datasheet/2/903/ds180_7Series_Overview-1591537.pdf"
			(at 200.66 100.33 0)
			(effects
				(font
					(size 1.27 1.27)
					(thickness 0.15)
				)
				(justify left bottom)
				(hide yes)
			)
		)
		(property "Description" ""
			(at 200.66 124.46 0)
			(effects
				(font
					(size 1.27 1.27)
				)
			)
		)
		(property "Manufacturer" "AMD-Xilinx"
			(at 200.66 102.87 0)
			(effects
				(font
					(size 1.27 1.27)
					(thickness 0.15)
				)
				(justify left bottom)
				(hide yes)
			)
		)
		(property "MPN" "XC7K410T-2FFG900I"
			(at 200.66 105.41 0)
			(effects
				(font
					(size 1.27 1.27)
					(thickness 0.15)
				)
				(justify left bottom)
				(hide yes)
			)
		)
		(property "Author" "Antmicro"
			(at 200.66 107.95 0)
			(effects
				(font
					(size 1.27 1.27)
					(thickness 0.15)
				)
				(justify left bottom)
				(hide yes)
			)
		)
		(property "License" "Apache-2.0"
			(at 200.66 110.49 0)
			(effects
				(font
					(size 1.27 1.27)
					(thickness 0.15)
				)
				(justify left bottom)
				(hide yes)
			)
		)
		(pin "A10"
		)
		(pin "AB1"
		)
		(pin "AB2"
		)
		(pin "AB5"
		)
		(pin "B10"
		)
		(pin "E10"
		)
		(pin "F10"
		)
		(pin "G10"
		)
		(pin "H10"
		)
		(pin "K10"
		)
		(pin "L10"
		)
		(pin "M10"
		)
		(pin "R14"
		)
		(pin "R15"
		)
		(pin "T14"
		)
		(pin "T15"
		)
		(pin "U14"
		)
		(pin "U15"
		)
		(pin "AA20"
		)
		(pin "AA21"
		)
		(pin "AA22"
		)
		(pin "AA23"
		)
		(pin "AB20"
		)
		(pin "AB22"
		)
		(pin "AB23"
		)
		(pin "AB24"
		)
		(pin "AC20"
		)
		(pin "AC21"
		)
		(pin "AC22"
		)
		(pin "AC24"
		)
		(pin "AC25"
		)
		(pin "AD21"
		)
		(pin "AD22"
		)
		(pin "AD23"
		)
		(pin "AD24"
		)
		(pin "AE20"
		)
		(pin "AE21"
		)
		(pin "AE23"
		)
		(pin "AE24"
		)
		(pin "AE25"
		)
		(pin "AF20"
		)
		(pin "AF21"
		)
		(pin "AF22"
		)
		(pin "AF23"
		)
		(pin "AF25"
		)
		(pin "AG20"
		)
		(pin "AG22"
		)
		(pin "AG23"
		)
		(pin "AG24"
		)
		(pin "AG25"
		)
		(pin "AH20"
		)
		(pin "AH21"
		)
		(pin "AH22"
		)
		(pin "AH24"
		)
		(pin "AH25"
		)
		(pin "AJ21"
		)
		(pin "AJ22"
		)
		(pin "AJ23"
		)
		(pin "AJ24"
		)
		(pin "AK20"
		)
		(pin "AK21"
		)
		(pin "AK23"
		)
		(pin "AK24"
		)
		(pin "AK25"
		)
		(pin "Y20"
		)
		(pin "Y21"
		)
		(pin "Y23"
		)
		(pin "Y24"
		)
		(pin "P24"
		)
		(pin "P26"
		)
		(pin "P27"
		)
		(pin "P28"
		)
		(pin "P29"
		)
		(pin "R19"
		)
		(pin "R20"
		)
		(pin "R21"
		)
		(pin "R23"
		)
		(pin "R24"
		)
		(pin "R25"
		)
		(pin "R26"
		)
		(pin "R28"
		)
		(pin "R29"
		)
		(pin "R30"
		)
		(pin "T20"
		)
		(pin "T21"
		)
		(pin "T22"
		)
		(pin "T23"
		)
		(pin "T25"
		)
		(pin "T26"
		)
		(pin "T27"
		)
		(pin "T28"
		)
		(pin "T30"
		)
		(pin "U19"
		)
		(pin "U20"
		)
		(pin "U22"
		)
		(pin "U23"
		)
		(pin "U24"
		)
		(pin "U25"
		)
		(pin "U27"
		)
		(pin "U28"
		)
		(pin "U29"
		)
		(pin "U30"
		)
		(pin "V19"
		)
		(pin "V20"
		)
		(pin "V21"
		)
		(pin "V22"
		)
		(pin "V24"
		)
		(pin "V25"
		)
		(pin "V26"
		)
		(pin "V27"
		)
		(pin "V29"
		)
		(pin "V30"
		)
		(pin "W19"
		)
		(pin "W21"
		)
		(pin "W22"
		)
		(pin "W23"
		)
		(pin "W24"
		)
		(pin "W26"
		)
		(pin "A23"
		)
		(pin "A25"
		)
		(pin "A26"
		)
		(pin "A27"
		)
		(pin "A28"
		)
		(pin "A30"
		)
		(pin "B23"
		)
		(pin "B24"
		)
		(pin "B25"
		)
		(pin "B27"
		)
		(pin "B28"
		)
		(pin "B29"
		)
		(pin "B30"
		)
		(pin "C24"
		)
		(pin "C25"
		)
		(pin "C26"
		)
		(pin "C27"
		)
		(pin "C29"
		)
		(pin "C30"
		)
		(pin "D23"
		)
		(pin "D24"
		)
		(pin "D26"
		)
		(pin "D27"
		)
		(pin "D28"
		)
		(pin "D29"
		)
		(pin "E23"
		)
		(pin "E24"
		)
		(pin "E25"
		)
		(pin "E26"
		)
		(pin "B2"
		)
		(pin "B5"
		)
		(pin "B6"
		)
		(pin "C3"
		)
		(pin "C4"
		)
		(pin "E28"
		)
		(pin "E29"
		)
		(pin "E30"
		)
		(pin "F23"
		)
		(pin "F25"
		)
		(pin "F26"
		)
		(pin "F27"
		)
		(pin "F28"
		)
		(pin "F30"
		)
		(pin "G23"
		)
		(pin "G24"
		)
		(pin "G25"
		)
		(pin "G27"
		)
		(pin "G28"
		)
		(pin "G29"
		)
		(pin "G30"
		)
		(pin "H24"
		)
		(pin "H25"
		)
		(pin "H26"
		)
		(pin "H27"
		)
		(pin "H30"
		)
		(pin "A11"
		)
		(pin "A12"
		)
		(pin "A13"
		)
		(pin "A15"
		)
		(pin "B12"
		)
		(pin "B13"
		)
		(pin "B14"
		)
		(pin "B15"
		)
		(pin "C11"
		)
		(pin "C12"
		)
		(pin "C14"
		)
		(pin "C15"
		)
		(pin "D11"
		)
		(pin "D12"
		)
		(pin "D13"
		)
		(pin "D14"
		)
		(pin "E11"
		)
		(pin "E13"
		)
		(pin "E14"
		)
		(pin "E15"
		)
		(pin "E16"
		)
		(pin "F11"
		)
		(pin "F12"
		)
		(pin "F13"
		)
		(pin "F15"
		)
		(pin "F16"
		)
		(pin "G12"
		)
		(pin "G13"
		)
		(pin "G14"
		)
		(pin "G15"
		)
		(pin "H11"
		)
		(pin "H12"
		)
		(pin "H14"
		)
		(pin "H15"
		)
		(pin "H16"
		)
		(pin "J11"
		)
		(pin "J12"
		)
		(pin "J13"
		)
		(pin "J14"
		)
		(pin "J16"
		)
		(pin "K11"
		)
		(pin "K13"
		)
		(pin "K14"
		)
		(pin "K15"
		)
		(pin "K16"
		)
		(pin "L11"
		)
		(pin "L12"
		)
		(pin "L13"
		)
		(pin "L15"
		)
		(pin "L16"
		)
		(pin "AA10"
		)
		(pin "AA11"
		)
		(pin "AA12"
		)
		(pin "AA13"
		)
		(pin "AA8"
		)
		(pin "AB10"
		)
		(pin "AB12"
		)
		(pin "AB13"
		)
		(pin "AB8"
		)
		(pin "AB9"
		)
		(pin "AC10"
		)
		(pin "AC11"
		)
		(pin "AC12"
		)
		(pin "AC9"
		)
		(pin "AD11"
		)
		(pin "AD12"
		)
		(pin "AD13"
		)
		(pin "AD8"
		)
		(pin "AD9"
		)
		(pin "AE10"
		)
		(pin "AE11"
		)
		(pin "AE13"
		)
		(pin "AE8"
		)
		(pin "AE9"
		)
		(pin "AF10"
		)
		(pin "AF11"
		)
		(pin "AF12"
		)
		(pin "AF13"
		)
		(pin "AG10"
		)
		(pin "AG12"
		)
		(pin "AG13"
		)
		(pin "AG9"
		)
		(pin "AH10"
		)
		(pin "AH11"
		)
		(pin "AH12"
		)
		(pin "AH14"
		)
		(pin "AH9"
		)
		(pin "AJ11"
		)
		(pin "AJ12"
		)
		(pin "AJ13"
		)
		(pin "AJ14"
		)
		(pin "AJ9"
		)
		(pin "AK10"
		)
		(pin "AK11"
		)
		(pin "AK13"
		)
		(pin "AK14"
		)
		(pin "AK9"
		)
		(pin "Y10"
		)
		(pin "Y11"
		)
		(pin "Y13"
		)
		(pin "A3"
		)
		(pin "A4"
		)
		(pin "A7"
		)
		(pin "A8"
		)
		(pin "AA3"
		)
		(pin "AA4"
		)
		(pin "B1"
		)
		(pin "G16"
		)
		(pin "G2"
		)
		(pin "G26"
		)
		(pin "G6"
		)
		(pin "G9"
		)
		(pin "H13"
		)
		(pin "H23"
		)
		(pin "H4"
		)
		(pin "H8"
		)
		(pin "H9"
		)
		(pin "J1"
		)
		(pin "J10"
		)
		(pin "C7"
		)
		(pin "C8"
		)
		(pin "D1"
		)
		(pin "D2"
		)
		(pin "D5"
		)
		(pin "D6"
		)
		(pin "E3"
		)
		(pin "E4"
		)
		(pin "E7"
		)
		(pin "E8"
		)
		(pin "F1"
		)
		(pin "F2"
		)
		(pin "F5"
		)
		(pin "F6"
		)
		(pin "G3"
		)
		(pin "G4"
		)
		(pin "G7"
		)
		(pin "G8"
		)
		(pin "H1"
		)
		(pin "H2"
		)
		(pin "H5"
		)
		(pin "H6"
		)
		(pin "J3"
		)
		(pin "J4"
		)
		(pin "J7"
		)
		(pin "J8"
		)
		(pin "K1"
		)
		(pin "K2"
		)
		(pin "K5"
		)
		(pin "K6"
		)
		(pin "L3"
		)
		(pin "L4"
		)
		(pin "L7"
		)
		(pin "L8"
		)
		(pin "M1"
		)
		(pin "M2"
		)
		(pin "M5"
		)
		(pin "M6"
		)
		(pin "N3"
		)
		(pin "N4"
		)
		(pin "N7"
		)
		(pin "N8"
		)
		(pin "P1"
		)
		(pin "P2"
		)
		(pin "P5"
		)
		(pin "P6"
		)
		(pin "R3"
		)
		(pin "R4"
		)
		(pin "R7"
		)
		(pin "R8"
		)
		(pin "T1"
		)
		(pin "T2"
		)
		(pin "T5"
		)
		(pin "T6"
		)
		(pin "U3"
		)
		(pin "U4"
		)
		(pin "U7"
		)
		(pin "U8"
		)
		(pin "V1"
		)
		(pin "V2"
		)
		(pin "V5"
		)
		(pin "V6"
		)
		(pin "W3"
		)
		(pin "W4"
		)
		(pin "Y1"
		)
		(pin "Y2"
		)
		(pin "Y5"
		)
		(pin "Y6"
		)
		(pin "B3"
		)
		(pin "B7"
		)
		(pin "C5"
		)
		(pin "D3"
		)
		(pin "D7"
		)
		(pin "E5"
		)
		(pin "F3"
		)
		(pin "F7"
		)
		(pin "G5"
		)
		(pin "H3"
		)
		(pin "H7"
		)
		(pin "J5"
		)
		(pin "K3"
		)
		(pin "K7"
		)
		(pin "L5"
		)
		(pin "M3"
		)
		(pin "M7"
		)
		(pin "N5"
		)
		(pin "P3"
		)
		(pin "P7"
		)
		(pin "R5"
		)
		(pin "T3"
		)
		(pin "T7"
		)
		(pin "U5"
		)
		(pin "V3"
		)
		(pin "V7"
		)
		(pin "W5"
		)
		(pin "W7"
		)
		(pin "W8"
		)
		(pin "A19"
		)
		(pin "A29"
		)
		(pin "AA19"
		)
		(pin "AA29"
		)
		(pin "AA9"
		)
		(pin "AB16"
		)
		(pin "AB26"
		)
		(pin "AB6"
		)
		(pin "AC13"
		)
		(pin "AC23"
		)
		(pin "AC3"
		)
		(pin "AD10"
		)
		(pin "AD20"
		)
		(pin "AD30"
		)
		(pin "AE17"
		)
		(pin "AE27"
		)
		(pin "AE7"
		)
		(pin "AF14"
		)
		(pin "AF24"
		)
		(pin "AF4"
		)
		(pin "AG1"
		)
		(pin "AG11"
		)
		(pin "AG21"
		)
		(pin "AH18"
		)
		(pin "AH28"
		)
		(pin "AH8"
		)
		(pin "AJ15"
		)
		(pin "AJ25"
		)
		(pin "AJ5"
		)
		(pin "AK12"
		)
		(pin "AK2"
		)
		(pin "AK22"
		)
		(pin "B16"
		)
		(pin "B26"
		)
		(pin "C13"
		)
		(pin "C23"
		)
		(pin "D10"
		)
		(pin "D20"
		)
		(pin "D30"
		)
		(pin "E17"
		)
		(pin "E27"
		)
		(pin "F14"
		)
		(pin "F24"
		)
		(pin "G11"
		)
		(pin "G21"
		)
		(pin "H18"
		)
		(pin "H28"
		)
		(pin "J15"
		)
		(pin "J25"
		)
		(pin "K12"
		)
		(pin "K22"
		)
		(pin "L19"
		)
		(pin "L29"
		)
		(pin "M26"
		)
		(pin "N23"
		)
		(pin "P20"
		)
		(pin "P30"
		)
		(pin "R27"
		)
		(pin "T24"
		)
		(pin "T9"
		)
		(pin "U21"
		)
		(pin "V28"
		)
		(pin "W25"
		)
		(pin "Y12"
		)
		(pin "Y22"
		)
		(pin "A1"
		)
		(pin "A14"
		)
		(pin "A2"
		)
		(pin "A24"
		)
		(pin "A5"
		)
		(pin "A6"
		)
		(pin "A9"
		)
		(pin "AA1"
		)
		(pin "AA14"
		)
		(pin "AA2"
		)
		(pin "AA24"
		)
		(pin "AA5"
		)
		(pin "AA6"
		)
		(pin "AA7"
		)
		(pin "AB11"
		)
		(pin "AB21"
		)
		(pin "AB3"
		)
		(pin "AB4"
		)
		(pin "AC18"
		)
		(pin "AC28"
		)
		(pin "AC8"
		)
		(pin "AD15"
		)
		(pin "AD25"
		)
		(pin "AD5"
		)
		(pin "AE12"
		)
		(pin "AE2"
		)
		(pin "AE22"
		)
		(pin "AF19"
		)
		(pin "AF29"
		)
		(pin "AF9"
		)
		(pin "AG16"
		)
		(pin "AG26"
		)
		(pin "AG6"
		)
		(pin "AH13"
		)
		(pin "AH23"
		)
		(pin "AH3"
		)
		(pin "AJ10"
		)
		(pin "AJ20"
		)
		(pin "AJ30"
		)
		(pin "AK17"
		)
		(pin "AK27"
		)
		(pin "AK7"
		)
		(pin "B11"
		)
		(pin "B21"
		)
		(pin "B4"
		)
		(pin "B8"
		)
		(pin "B9"
		)
		(pin "C1"
		)
		(pin "C10"
		)
		(pin "C18"
		)
		(pin "C2"
		)
		(pin "C28"
		)
		(pin "C6"
		)
		(pin "C9"
		)
		(pin "D15"
		)
		(pin "D25"
		)
		(pin "D4"
		)
		(pin "D8"
		)
		(pin "D9"
		)
		(pin "E1"
		)
		(pin "E12"
		)
		(pin "E2"
		)
		(pin "E22"
		)
		(pin "E6"
		)
		(pin "E9"
		)
		(pin "F19"
		)
		(pin "F29"
		)
		(pin "F4"
		)
		(pin "F8"
		)
		(pin "F9"
		)
		(pin "G1"
		)
		(pin "J2"
		)
		(pin "J20"
		)
		(pin "J30"
		)
		(pin "J6"
		)
		(pin "J9"
		)
		(pin "K17"
		)
		(pin "K27"
		)
		(pin "K4"
		)
		(pin "K8"
		)
		(pin "K9"
		)
		(pin "L1"
		)
		(pin "L14"
		)
		(pin "L2"
		)
		(pin "L24"
		)
		(pin "L6"
		)
		(pin "L9"
		)
		(pin "M11"
		)
		(pin "M12"
		)
		(pin "M13"
		)
		(pin "M14"
		)
		(pin "M15"
		)
		(pin "M16"
		)
		(pin "M17"
		)
		(pin "M18"
		)
		(pin "M21"
		)
		(pin "M4"
		)
		(pin "M8"
		)
		(pin "M9"
		)
		(pin "N1"
		)
		(pin "N10"
		)
		(pin "N11"
		)
		(pin "N12"
		)
		(pin "N13"
		)
		(pin "N14"
		)
		(pin "N15"
		)
		(pin "N16"
		)
		(pin "N17"
		)
		(pin "N18"
		)
		(pin "N2"
		)
		(pin "N28"
		)
		(pin "N6"
		)
		(pin "N9"
		)
		(pin "P10"
		)
		(pin "P11"
		)
		(pin "P12"
		)
		(pin "P13"
		)
		(pin "P14"
		)
		(pin "P15"
		)
		(pin "P16"
		)
		(pin "P17"
		)
		(pin "P18"
		)
		(pin "P25"
		)
		(pin "P4"
		)
		(pin "P8"
		)
		(pin "P9"
		)
		(pin "R1"
		)
		(pin "R10"
		)
		(pin "R11"
		)
		(pin "R12"
		)
		(pin "R13"
		)
		(pin "R16"
		)
		(pin "R17"
		)
		(pin "R18"
		)
		(pin "R2"
		)
		(pin "R22"
		)
		(pin "R6"
		)
		(pin "R9"
		)
		(pin "T10"
		)
		(pin "T11"
		)
		(pin "T12"
		)
		(pin "T13"
		)
		(pin "T16"
		)
		(pin "T17"
		)
		(pin "T18"
		)
		(pin "T19"
		)
		(pin "T29"
		)
		(pin "T4"
		)
		(pin "T8"
		)
		(pin "U1"
		)
		(pin "U10"
		)
		(pin "U11"
		)
		(pin "U12"
		)
		(pin "U13"
		)
		(pin "U16"
		)
		(pin "U17"
		)
		(pin "U18"
		)
		(pin "U2"
		)
		(pin "U26"
		)
		(pin "U6"
		)
		(pin "U9"
		)
		(pin "V10"
		)
		(pin "V11"
		)
		(pin "V12"
		)
		(pin "V13"
		)
		(pin "V14"
		)
		(pin "V15"
		)
		(pin "V16"
		)
		(pin "V17"
		)
		(pin "V18"
		)
		(pin "V23"
		)
		(pin "V4"
		)
		(pin "V8"
		)
		(pin "V9"
		)
		(pin "W1"
		)
		(pin "W10"
		)
		(pin "W11"
		)
		(pin "W12"
		)
		(pin "W13"
		)
		(pin "W14"
		)
		(pin "W15"
		)
		(pin "W16"
		)
		(pin "W17"
		)
		(pin "W18"
		)
		(pin "W2"
		)
		(pin "W20"
		)
		(pin "W30"
		)
		(pin "W6"
		)
		(pin "W9"
		)
		(pin "Y17"
		)
		(pin "Y27"
		)
		(pin "Y3"
		)
		(pin "Y4"
		)
		(pin "Y7"
		)
		(pin "Y8"
		)
		(pin "Y9"
		)
		(pin "AA25"
		)
		(pin "AA26"
		)
		(pin "AA27"
		)
		(pin "AA28"
		)
		(pin "AA30"
		)
		(pin "AB25"
		)
		(pin "AB27"
		)
		(pin "AB28"
		)
		(pin "AB29"
		)
		(pin "AB30"
		)
		(pin "AC26"
		)
		(pin "AC27"
		)
		(pin "AC29"
		)
		(pin "AC30"
		)
		(pin "AD26"
		)
		(pin "AD27"
		)
		(pin "AD28"
		)
		(pin "AD29"
		)
		(pin "AE26"
		)
		(pin "AE28"
		)
		(pin "AE29"
		)
		(pin "AE30"
		)
		(pin "AF26"
		)
		(pin "AF27"
		)
		(pin "AF28"
		)
		(pin "AF30"
		)
		(pin "AG27"
		)
		(pin "AG28"
		)
		(pin "AG29"
		)
		(pin "AG30"
		)
		(pin "AH26"
		)
		(pin "AH27"
		)
		(pin "AH29"
		)
		(pin "AH30"
		)
		(pin "AJ26"
		)
		(pin "AJ27"
		)
		(pin "AJ28"
		)
		(pin "AJ29"
		)
		(pin "AK26"
		)
		(pin "AK28"
		)
		(pin "AK29"
		)
		(pin "AK30"
		)
		(pin "W27"
		)
		(pin "W28"
		)
		(pin "W29"
		)
		(pin "Y25"
		)
		(pin "Y26"
		)
		(pin "Y28"
		)
		(pin "Y29"
		)
		(pin "Y30"
		)
		(pin "H29"
		)
		(pin "J21"
		)
		(pin "J22"
		)
		(pin "J23"
		)
		(pin "J24"
		)
		(pin "J26"
		)
		(pin "J27"
		)
		(pin "J28"
		)
		(pin "J29"
		)
		(pin "K21"
		)
		(pin "K23"
		)
		(pin "K24"
		)
		(pin "K25"
		)
		(pin "K26"
		)
		(pin "K28"
		)
		(pin "K29"
		)
		(pin "K30"
		)
		(pin "L20"
		)
		(pin "L21"
		)
		(pin "L22"
		)
		(pin "L23"
		)
		(pin "L25"
		)
		(pin "L26"
		)
		(pin "L27"
		)
		(pin "L28"
		)
		(pin "L30"
		)
		(pin "M19"
		)
		(pin "M20"
		)
		(pin "M22"
		)
		(pin "M23"
		)
		(pin "M24"
		)
		(pin "M25"
		)
		(pin "M27"
		)
		(pin "M28"
		)
		(pin "M29"
		)
		(pin "M30"
		)
		(pin "N19"
		)
		(pin "N20"
		)
		(pin "N21"
		)
		(pin "N22"
		)
		(pin "N24"
		)
		(pin "N25"
		)
		(pin "N26"
		)
		(pin "N27"
		)
		(pin "N29"
		)
		(pin "N30"
		)
		(pin "P19"
		)
		(pin "P21"
		)
		(pin "P22"
		)
		(pin "P23"
		)
		(pin "A16"
		)
		(pin "A17"
		)
		(pin "A18"
		)
		(pin "A20"
		)
		(pin "A21"
		)
		(pin "A22"
		)
		(pin "B17"
		)
		(pin "B18"
		)
		(pin "B19"
		)
		(pin "B20"
		)
		(pin "B22"
		)
		(pin "C16"
		)
		(pin "C17"
		)
		(pin "C19"
		)
		(pin "C20"
		)
		(pin "C21"
		)
		(pin "C22"
		)
		(pin "D16"
		)
		(pin "D17"
		)
		(pin "D18"
		)
		(pin "D19"
		)
		(pin "D21"
		)
		(pin "D22"
		)
		(pin "E18"
		)
		(pin "E19"
		)
		(pin "E20"
		)
		(pin "E21"
		)
		(pin "F17"
		)
		(pin "F18"
		)
		(pin "F20"
		)
		(pin "F21"
		)
		(pin "F22"
		)
		(pin "G17"
		)
		(pin "G18"
		)
		(pin "G19"
		)
		(pin "G20"
		)
		(pin "G22"
		)
		(pin "H17"
		)
		(pin "H19"
		)
		(pin "H20"
		)
		(pin "H21"
		)
		(pin "H22"
		)
		(pin "J17"
		)
		(pin "J18"
		)
		(pin "J19"
		)
		(pin "K18"
		)
		(pin "K19"
		)
		(pin "K20"
		)
		(pin "L17"
		)
		(pin "L18"
		)
		(pin "AA15"
		)
		(pin "AA16"
		)
		(pin "AA17"
		)
		(pin "AA18"
		)
		(pin "AB14"
		)
		(pin "AB15"
		)
		(pin "AB17"
		)
		(pin "AB18"
		)
		(pin "AB19"
		)
		(pin "AC14"
		)
		(pin "AC15"
		)
		(pin "AC16"
		)
		(pin "AC17"
		)
		(pin "AC19"
		)
		(pin "AD14"
		)
		(pin "AD16"
		)
		(pin "AD17"
		)
		(pin "AD18"
		)
		(pin "AD19"
		)
		(pin "AE14"
		)
		(pin "AE15"
		)
		(pin "AE16"
		)
		(pin "AE18"
		)
		(pin "AE19"
		)
		(pin "AF15"
		)
		(pin "AF16"
		)
		(pin "AF17"
		)
		(pin "AF18"
		)
		(pin "AG14"
		)
		(pin "AG15"
		)
		(pin "AG17"
		)
		(pin "AG18"
		)
		(pin "AG19"
		)
		(pin "AH15"
		)
		(pin "AH16"
		)
		(pin "AH17"
		)
		(pin "AH19"
		)
		(pin "AJ16"
		)
		(pin "AJ17"
		)
		(pin "AJ18"
		)
		(pin "AJ19"
		)
		(pin "AK15"
		)
		(pin "AK16"
		)
		(pin "AK18"
		)
		(pin "AK19"
		)
		(pin "Y14"
		)
		(pin "Y15"
		)
		(pin "Y16"
		)
		(pin "Y18"
		)
		(pin "Y19"
		)
		(pin "AB7"
		)
		(pin "AC1"
		)
		(pin "AC2"
		)
		(pin "AC4"
		)
		(pin "AC5"
		)
		(pin "AC6"
		)
		(pin "AC7"
		)
		(pin "AD1"
		)
		(pin "AD2"
		)
		(pin "AD3"
		)
		(pin "AD4"
		)
		(pin "AD6"
		)
		(pin "AD7"
		)
		(pin "AE1"
		)
		(pin "AE3"
		)
		(pin "AE4"
		)
		(pin "AE5"
		)
		(pin "AE6"
		)
		(pin "AF1"
		)
		(pin "AF2"
		)
		(pin "AF3"
		)
		(pin "AF5"
		)
		(pin "AF6"
		)
		(pin "AF7"
		)
		(pin "AF8"
		)
		(pin "AG2"
		)
		(pin "AG3"
		)
		(pin "AG4"
		)
		(pin "AG5"
		)
		(pin "AG7"
		)
		(pin "AG8"
		)
		(pin "AH1"
		)
		(pin "AH2"
		)
		(pin "AH4"
		)
		(pin "AH5"
		)
		(pin "AH6"
		)
		(pin "AH7"
		)
		(pin "AJ1"
		)
		(pin "AJ2"
		)
		(pin "AJ3"
		)
		(pin "AJ4"
		)
		(pin "AJ6"
		)
		(pin "AJ7"
		)
		(pin "AJ8"
		)
		(pin "AK1"
		)
		(pin "AK3"
		)
		(pin "AK4"
		)
		(pin "AK5"
		)
		(pin "AK6"
		)
		(pin "AK8"
		)
		(instances
			(project "k410t-devboard"
				(path ""
					(reference "U1")
					(unit 9)
				)
			)
		)
	)
	(symbol
		(lib_id "antmicroTransistorsFETsMOSFETsSingle:BSS138PW")
		(at 355.6 124.46 90)
		(unit 1)
		(exclude_from_sim no)
		(in_bom yes)
		(on_board yes)
		(dnp no)
		(fields_autoplaced yes)
		(property "Reference" "Q2"
			(at 353.06 109.22 90)
			(effects
				(font
					(size 1.27 1.27)
				)
			)
		)
		(property "Value" "BSS138PW"
			(at 353.06 111.76 90)
			(effects
				(font
					(size 1.27 1.27)
					(thickness 0.15)
				)
			)
		)
		(property "Footprint" "antmicro-footprints:SC70-3"
			(at 367.03 101.6 0)
			(effects
				(font
					(size 1.27 1.27)
					(thickness 0.15)
				)
				(justify left bottom)
				(hide yes)
			)
		)
		(property "Datasheet" "https://assets.nexperia.com/documents/data-sheet/BSS138PW.pdf"
			(at 369.57 101.6 0)
			(effects
				(font
					(size 1.27 1.27)
					(thickness 0.15)
				)
				(justify left bottom)
				(hide yes)
			)
		)
		(property "Description" ""
			(at 355.6 124.46 0)
			(effects
				(font
					(size 1.27 1.27)
				)
			)
		)
		(property "MPN" "BSS138PW"
			(at 372.11 101.6 0)
			(effects
				(font
					(size 1.27 1.27)
					(thickness 0.15)
				)
				(justify left bottom)
				(hide yes)
			)
		)
		(property "Manufacturer" "Nexperia"
			(at 374.65 101.6 0)
			(effects
				(font
					(size 1.27 1.27)
					(thickness 0.15)
				)
				(justify left bottom)
				(hide yes)
			)
		)
		(property "Author" "Antmicro"
			(at 377.19 101.6 0)
			(effects
				(font
					(size 1.27 1.27)
					(thickness 0.15)
				)
				(justify left bottom)
				(hide yes)
			)
		)
		(property "License" "Apache-2.0"
			(at 379.73 101.6 0)
			(effects
				(font
					(size 1.27 1.27)
					(thickness 0.15)
				)
				(justify left bottom)
				(hide yes)
			)
		)
		(pin "1"
		)
		(pin "2"
		)
		(pin "3"
		)
		(instances
			(project "k410t-devboard"
				(path ""
					(reference "Q2")
					(unit 1)
				)
			)
		)
	)
	(symbol
		(lib_id "antmicroResistors0402:R_10k_0402")
		(at 238.76 120.65 90)
		(unit 1)
		(exclude_from_sim no)
		(in_bom yes)
		(on_board yes)
		(dnp no)
		(property "Reference" "R5"
			(at 240.03 116.84 90)
			(effects
				(font
					(size 1.27 1.27)
				)
				(justify right)
			)
		)
		(property "Value" "R_10k_0402"
			(at 251.46 100.33 0)
			(effects
				(font
					(size 1.27 1.27)
					(thickness 0.15)
				)
				(justify left bottom)
				(hide yes)
			)
		)
		(property "Footprint" "antmicro-footprints:R_0402_1005Metric"
			(at 254 100.33 0)
			(effects
				(font
					(size 1.27 1.27)
					(thickness 0.15)
				)
				(justify left bottom)
				(hide yes)
			)
		)
		(property "Datasheet" "https://www.bourns.com/docs/product-datasheets/cr.pdf"
			(at 256.54 100.33 0)
			(effects
				(font
					(size 1.27 1.27)
					(thickness 0.15)
				)
				(justify left bottom)
				(hide yes)
			)
		)
		(property "Description" ""
			(at 238.76 120.65 0)
			(effects
				(font
					(size 1.27 1.27)
				)
			)
		)
		(property "Manufacturer" "Bourns"
			(at 261.62 100.33 0)
			(effects
				(font
					(size 1.27 1.27)
					(thickness 0.15)
				)
				(justify left bottom)
				(hide yes)
			)
		)
		(property "MPN" "CR0402-FX-1002GLF"
			(at 259.08 100.33 0)
			(effects
				(font
					(size 1.27 1.27)
					(thickness 0.15)
				)
				(justify left bottom)
				(hide yes)
			)
		)
		(property "Val" "10k"
			(at 240.03 119.38 90)
			(effects
				(font
					(size 1.27 1.27)
					(thickness 0.15)
				)
				(justify right)
			)
		)
		(property "License" "Apache-2.0"
			(at 264.16 100.33 0)
			(effects
				(font
					(size 1.27 1.27)
					(thickness 0.15)
				)
				(justify left bottom)
				(hide yes)
			)
		)
		(property "Author" "Antmicro"
			(at 266.7 100.33 0)
			(effects
				(font
					(size 1.27 1.27)
					(thickness 0.15)
				)
				(justify left bottom)
				(hide yes)
			)
		)
		(property "Tolerance" "1%"
			(at 248.92 100.33 0)
			(effects
				(font
					(size 1.27 1.27)
				)
				(justify left bottom)
				(hide yes)
			)
		)
		(pin "1"
		)
		(pin "2"
		)
		(instances
			(project "k410t-devboard"
				(path ""
					(reference "R5")
					(unit 1)
				)
			)
		)
	)
	(symbol
		(lib_id "antmicropower:+3.3V")
		(at 118.11 118.11 0)
		(mirror y)
		(unit 1)
		(exclude_from_sim no)
		(in_bom yes)
		(on_board yes)
		(dnp no)
		(fields_autoplaced yes)
		(property "Reference" "#PWR047"
			(at 118.11 121.92 0)
			(effects
				(font
					(size 1.27 1.27)
				)
				(hide yes)
			)
		)
		(property "Value" "+3V3"
			(at 118.11 114.554 0)
			(effects
				(font
					(size 1.27 1.27)
				)
			)
		)
		(property "Footprint" ""
			(at 118.11 118.11 0)
			(effects
				(font
					(size 1.27 1.27)
				)
				(hide yes)
			)
		)
		(property "Datasheet" ""
			(at 118.11 118.11 0)
			(effects
				(font
					(size 1.27 1.27)
				)
				(hide yes)
			)
		)
		(property "Description" ""
			(at 118.11 118.11 0)
			(effects
				(font
					(size 1.27 1.27)
				)
			)
		)
		(pin "1"
		)
		(instances
			(project "k410t-devboard"
				(path ""
					(reference "#PWR047")
					(unit 1)
				)
			)
		)
	)
	(symbol
		(lib_id "antmicropower:GND")
		(at 299.72 173.99 0)
		(unit 1)
		(exclude_from_sim no)
		(in_bom yes)
		(on_board yes)
		(dnp no)
		(property "Reference" "#PWR049"
			(at 299.72 180.34 0)
			(effects
				(font
					(size 1.27 1.27)
				)
				(hide yes)
			)
		)
		(property "Value" "GND"
			(at 299.72 177.8 0)
			(effects
				(font
					(size 1.27 1.27)
				)
			)
		)
		(property "Footprint" ""
			(at 308.61 181.61 0)
			(effects
				(font
					(size 1.27 1.27)
					(thickness 0.15)
				)
				(justify left bottom)
				(hide yes)
			)
		)
		(property "Datasheet" ""
			(at 308.61 186.69 0)
			(effects
				(font
					(size 1.27 1.27)
					(thickness 0.15)
				)
				(justify left bottom)
				(hide yes)
			)
		)
		(property "Description" ""
			(at 299.72 173.99 0)
			(effects
				(font
					(size 1.27 1.27)
				)
			)
		)
		(property "Author" "Antmicro"
			(at 308.61 181.61 0)
			(effects
				(font
					(size 1.27 1.27)
					(thickness 0.15)
				)
				(justify left bottom)
				(hide yes)
			)
		)
		(property "License" "Apache-2.0"
			(at 308.61 184.15 0)
			(effects
				(font
					(size 1.27 1.27)
					(thickness 0.15)
				)
				(justify left bottom)
				(hide yes)
			)
		)
		(pin "1"
		)
		(instances
			(project "k410t-devboard"
				(path ""
					(reference "#PWR049")
					(unit 1)
				)
			)
		)
	)
	(symbol
		(lib_id "antmicroResistors0402:R_10k_0402")
		(at 110.49 127 270)
		(mirror x)
		(unit 1)
		(exclude_from_sim no)
		(in_bom no)
		(on_board yes)
		(dnp yes)
		(property "Reference" "R2"
			(at 111.76 123.19 90)
			(effects
				(font
					(size 1.27 1.27)
				)
				(justify left)
			)
		)
		(property "Value" "R_10k_0402"
			(at 97.79 106.68 0)
			(effects
				(font
					(size 1.27 1.27)
					(thickness 0.15)
				)
				(justify left bottom)
				(hide yes)
			)
		)
		(property "Footprint" "antmicro-footprints:R_0402_1005Metric"
			(at 95.25 106.68 0)
			(effects
				(font
					(size 1.27 1.27)
					(thickness 0.15)
				)
				(justify left bottom)
				(hide yes)
			)
		)
		(property "Datasheet" "https://www.bourns.com/docs/product-datasheets/cr.pdf"
			(at 92.71 106.68 0)
			(effects
				(font
					(size 1.27 1.27)
					(thickness 0.15)
				)
				(justify left bottom)
				(hide yes)
			)
		)
		(property "Description" ""
			(at 110.49 127 0)
			(effects
				(font
					(size 1.27 1.27)
				)
			)
		)
		(property "Manufacturer" "Bourns"
			(at 87.63 106.68 0)
			(effects
				(font
					(size 1.27 1.27)
					(thickness 0.15)
				)
				(justify left bottom)
				(hide yes)
			)
		)
		(property "MPN" "CR0402-FX-1002GLF"
			(at 90.17 106.68 0)
			(effects
				(font
					(size 1.27 1.27)
					(thickness 0.15)
				)
				(justify left bottom)
				(hide yes)
			)
		)
		(property "Val" "10k"
			(at 111.76 125.73 90)
			(effects
				(font
					(size 1.27 1.27)
					(thickness 0.15)
				)
				(justify left)
			)
		)
		(property "DNP" "DNP"
			(at 110.49 126.365 0)
			(effects
				(font
					(size 1.27 1.27)
				)
				(justify left)
			)
		)
		(property "License" "Apache-2.0"
			(at 85.09 106.68 0)
			(effects
				(font
					(size 1.27 1.27)
					(thickness 0.15)
				)
				(justify left bottom)
				(hide yes)
			)
		)
		(property "Author" "Antmicro"
			(at 82.55 106.68 0)
			(effects
				(font
					(size 1.27 1.27)
					(thickness 0.15)
				)
				(justify left bottom)
				(hide yes)
			)
		)
		(property "Tolerance" "1%"
			(at 100.33 106.68 0)
			(effects
				(font
					(size 1.27 1.27)
				)
				(justify left bottom)
				(hide yes)
			)
		)
		(pin "1"
		)
		(pin "2"
		)
		(instances
			(project "k410t-devboard"
				(path ""
					(reference "R2")
					(unit 1)
				)
			)
		)
	)
	(symbol
		(lib_id "antmicropower:+3.3V")
		(at 326.39 114.3 0)
		(unit 1)
		(exclude_from_sim no)
		(in_bom yes)
		(on_board yes)
		(dnp no)
		(fields_autoplaced yes)
		(property "Reference" "#PWR053"
			(at 326.39 118.11 0)
			(effects
				(font
					(size 1.27 1.27)
				)
				(hide yes)
			)
		)
		(property "Value" "+3V3"
			(at 326.39 110.744 0)
			(effects
				(font
					(size 1.27 1.27)
				)
			)
		)
		(property "Footprint" ""
			(at 326.39 114.3 0)
			(effects
				(font
					(size 1.27 1.27)
				)
				(hide yes)
			)
		)
		(property "Datasheet" ""
			(at 326.39 114.3 0)
			(effects
				(font
					(size 1.27 1.27)
				)
				(hide yes)
			)
		)
		(property "Description" ""
			(at 326.39 114.3 0)
			(effects
				(font
					(size 1.27 1.27)
				)
			)
		)
		(pin "1"
		)
		(instances
			(project "k410t-devboard"
				(path ""
					(reference "#PWR053")
					(unit 1)
				)
			)
		)
	)
	(symbol
		(lib_id "antmicroLEDIndicationDiscrete:LED_G_0603_KP-1608CGCK")
		(at 335.28 95.25 0)
		(mirror y)
		(unit 1)
		(exclude_from_sim no)
		(in_bom yes)
		(on_board yes)
		(dnp no)
		(fields_autoplaced yes)
		(property "Reference" "D1"
			(at 332.74 87.63 0)
			(effects
				(font
					(size 1.27 1.27)
				)
			)
		)
		(property "Value" "LED_G_0603_KP-1608CGCK"
			(at 331.47 102.235 0)
			(effects
				(font
					(size 1.27 1.27)
					(thickness 0.15)
				)
				(justify left bottom)
				(hide yes)
			)
		)
		(property "Footprint" "antmicro-footprints:LED_0603_1608Metric_G"
			(at 312.42 105.41 0)
			(effects
				(font
					(size 1.27 1.27)
					(thickness 0.15)
				)
				(justify right bottom)
				(hide yes)
			)
		)
		(property "Datasheet" "http://www.kingbright.com/attachments/file/psearch//000/00/00/KP-1608CGCK(Ver.23B).pdf"
			(at 312.42 107.95 0)
			(effects
				(font
					(size 1.27 1.27)
					(thickness 0.15)
				)
				(justify right bottom)
				(hide yes)
			)
		)
		(property "Description" ""
			(at 335.28 95.25 0)
			(effects
				(font
					(size 1.27 1.27)
				)
			)
		)
		(property "MPN" "KP-1608CGCK"
			(at 312.42 110.49 0)
			(effects
				(font
					(size 1.27 1.27)
					(thickness 0.15)
				)
				(justify right bottom)
				(hide yes)
			)
		)
		(property "Manufacturer" "Kingbright"
			(at 312.42 113.03 0)
			(effects
				(font
					(size 1.27 1.27)
					(thickness 0.15)
				)
				(justify right bottom)
				(hide yes)
			)
		)
		(property "Author" "Antmicro"
			(at 312.42 115.57 0)
			(effects
				(font
					(size 1.27 1.27)
					(thickness 0.15)
				)
				(justify right bottom)
				(hide yes)
			)
		)
		(property "License" "Apache-2.0"
			(at 312.42 118.11 0)
			(effects
				(font
					(size 1.27 1.27)
					(thickness 0.15)
				)
				(justify right bottom)
				(hide yes)
			)
		)
		(property "Color" "Green"
			(at 332.74 90.17 0)
			(effects
				(font
					(size 1.27 1.27)
				)
			)
		)
		(pin "1"
		)
		(pin "2"
		)
		(instances
			(project "k410t-devboard"
				(path ""
					(reference "D1")
					(unit 1)
				)
			)
		)
	)
	(symbol
		(lib_id "antmicropower:+3.3V")
		(at 299.72 162.56 0)
		(unit 1)
		(exclude_from_sim no)
		(in_bom yes)
		(on_board yes)
		(dnp no)
		(fields_autoplaced yes)
		(property "Reference" "#PWR050"
			(at 299.72 166.37 0)
			(effects
				(font
					(size 1.27 1.27)
				)
				(hide yes)
			)
		)
		(property "Value" "+3V3"
			(at 299.72 159.004 0)
			(effects
				(font
					(size 1.27 1.27)
				)
			)
		)
		(property "Footprint" ""
			(at 299.72 162.56 0)
			(effects
				(font
					(size 1.27 1.27)
				)
				(hide yes)
			)
		)
		(property "Datasheet" ""
			(at 299.72 162.56 0)
			(effects
				(font
					(size 1.27 1.27)
				)
				(hide yes)
			)
		)
		(property "Description" ""
			(at 299.72 162.56 0)
			(effects
				(font
					(size 1.27 1.27)
				)
			)
		)
		(pin "1"
		)
		(instances
			(project "k410t-devboard"
				(path ""
					(reference "#PWR050")
					(unit 1)
				)
			)
		)
	)
	(symbol
		(lib_id "antmicropower:GND")
		(at 82.55 142.24 0)
		(mirror y)
		(unit 1)
		(exclude_from_sim no)
		(in_bom yes)
		(on_board yes)
		(dnp no)
		(property "Reference" "#PWR045"
			(at 82.55 148.59 0)
			(effects
				(font
					(size 1.27 1.27)
				)
				(hide yes)
			)
		)
		(property "Value" "GND"
			(at 82.55 146.05 0)
			(effects
				(font
					(size 1.27 1.27)
				)
			)
		)
		(property "Footprint" ""
			(at 73.66 149.86 0)
			(effects
				(font
					(size 1.27 1.27)
					(thickness 0.15)
				)
				(justify left bottom)
				(hide yes)
			)
		)
		(property "Datasheet" ""
			(at 73.66 154.94 0)
			(effects
				(font
					(size 1.27 1.27)
					(thickness 0.15)
				)
				(justify left bottom)
				(hide yes)
			)
		)
		(property "Description" ""
			(at 82.55 142.24 0)
			(effects
				(font
					(size 1.27 1.27)
				)
			)
		)
		(property "Author" "Antmicro"
			(at 73.66 149.86 0)
			(effects
				(font
					(size 1.27 1.27)
					(thickness 0.15)
				)
				(justify left bottom)
				(hide yes)
			)
		)
		(property "License" "Apache-2.0"
			(at 73.66 152.4 0)
			(effects
				(font
					(size 1.27 1.27)
					(thickness 0.15)
				)
				(justify left bottom)
				(hide yes)
			)
		)
		(pin "1"
		)
		(instances
			(project "k410t-devboard"
				(path ""
					(reference "#PWR045")
					(unit 1)
				)
			)
		)
	)
	(symbol
		(lib_id "antmicroResistors0402:R_330R_0402")
		(at 339.09 116.84 0)
		(unit 1)
		(exclude_from_sim no)
		(in_bom yes)
		(on_board yes)
		(dnp no)
		(property "Reference" "R10"
			(at 341.63 114.3 0)
			(effects
				(font
					(size 1.524 1.524)
				)
			)
		)
		(property "Value" "R_330R_0402"
			(at 359.41 129.54 0)
			(effects
				(font
					(size 1.27 1.27)
					(thickness 0.15)
				)
				(justify left bottom)
				(hide yes)
			)
		)
		(property "Footprint" "antmicro-footprints:R_0402_1005Metric"
			(at 359.41 132.08 0)
			(effects
				(font
					(size 1.27 1.27)
					(thickness 0.15)
				)
				(justify left bottom)
				(hide yes)
			)
		)
		(property "Datasheet" "https://www.bourns.com/docs/product-datasheets/cr.pdf"
			(at 359.41 134.62 0)
			(effects
				(font
					(size 1.27 1.27)
					(thickness 0.15)
				)
				(justify left bottom)
				(hide yes)
			)
		)
		(property "Description" ""
			(at 339.09 116.84 0)
			(effects
				(font
					(size 1.27 1.27)
				)
			)
		)
		(property "Manufacturer" "Bourns"
			(at 359.41 139.7 0)
			(effects
				(font
					(size 1.27 1.27)
					(thickness 0.15)
				)
				(justify left bottom)
				(hide yes)
			)
		)
		(property "MPN" "CR0402-FX-3300GLF"
			(at 359.41 137.16 0)
			(effects
				(font
					(size 1.27 1.27)
					(thickness 0.15)
				)
				(justify left bottom)
				(hide yes)
			)
		)
		(property "Val" "330R"
			(at 341.63 119.38 0)
			(effects
				(font
					(size 1.27 1.27)
					(thickness 0.15)
				)
			)
		)
		(property "License" "Apache-2.0"
			(at 359.41 142.24 0)
			(effects
				(font
					(size 1.27 1.27)
					(thickness 0.15)
				)
				(justify left bottom)
				(hide yes)
			)
		)
		(property "Author" "Antmicro"
			(at 359.41 144.78 0)
			(effects
				(font
					(size 1.27 1.27)
					(thickness 0.15)
				)
				(justify left bottom)
				(hide yes)
			)
		)
		(property "Tolerance" "1%"
			(at 359.41 127 0)
			(effects
				(font
					(size 1.27 1.27)
				)
				(justify left bottom)
				(hide yes)
			)
		)
		(pin "1"
		)
		(pin "2"
		)
		(instances
			(project "k410t-devboard"
				(path ""
					(reference "R10")
					(unit 1)
				)
			)
		)
	)
	(symbol
		(lib_id "antmicroCapacitors0603:C_47u_0603")
		(at 173.99 76.2 90)
		(unit 1)
		(exclude_from_sim no)
		(in_bom yes)
		(on_board yes)
		(dnp no)
		(property "Reference" "C2"
			(at 174.625 71.755 90)
			(effects
				(font
					(size 1.27 1.27)
				)
				(justify right)
			)
		)
		(property "Value" "C_47u_0603"
			(at 184.15 55.88 0)
			(effects
				(font
					(size 1.27 1.27)
					(thickness 0.15)
				)
				(justify left bottom)
				(hide yes)
			)
		)
		(property "Footprint" "antmicro-footprints:C_0603_1608Metric"
			(at 186.69 55.88 0)
			(effects
				(font
					(size 1.27 1.27)
					(thickness 0.15)
				)
				(justify left bottom)
				(hide yes)
			)
		)
		(property "Datasheet" "https://www.murata.com/products/productdetail?partno=GRM188R60J476ME15%23"
			(at 189.23 55.88 0)
			(effects
				(font
					(size 1.27 1.27)
					(thickness 0.15)
				)
				(justify left bottom)
				(hide yes)
			)
		)
		(property "Description" ""
			(at 173.99 76.2 0)
			(effects
				(font
					(size 1.27 1.27)
				)
			)
		)
		(property "Manufacturer" "Murata"
			(at 194.31 55.88 0)
			(effects
				(font
					(size 1.27 1.27)
					(thickness 0.15)
				)
				(justify left bottom)
				(hide yes)
			)
		)
		(property "MPN" "GRM188R60J476ME15D"
			(at 191.77 55.88 0)
			(effects
				(font
					(size 1.27 1.27)
					(thickness 0.15)
				)
				(justify left bottom)
				(hide yes)
			)
		)
		(property "Val" "47u"
			(at 174.625 75.565 90)
			(effects
				(font
					(size 1.27 1.27)
					(thickness 0.15)
				)
				(justify right)
			)
		)
		(property "License" "Apache-2.0"
			(at 196.85 55.88 0)
			(effects
				(font
					(size 1.27 1.27)
					(thickness 0.15)
				)
				(justify left bottom)
				(hide yes)
			)
		)
		(property "Author" "Antmicro"
			(at 199.39 55.88 0)
			(effects
				(font
					(size 1.27 1.27)
					(thickness 0.15)
				)
				(justify left bottom)
				(hide yes)
			)
		)
		(property "Voltage" ""
			(at 201.93 55.88 0)
			(effects
				(font
					(size 1.27 1.27)
				)
				(justify left bottom)
				(hide yes)
			)
		)
		(property "Dielectric" ""
			(at 204.47 55.88 0)
			(effects
				(font
					(size 1.27 1.27)
				)
				(justify left bottom)
				(hide yes)
			)
		)
		(pin "1"
		)
		(pin "2"
		)
		(instances
			(project "k410t-devboard"
				(path ""
					(reference "C2")
					(unit 1)
				)
			)
		)
	)
	(symbol
		(lib_id "antmicroTVSDiodes:TPD4E05U06QDQARQ1")
		(at 71.12 245.11 270)
		(unit 1)
		(exclude_from_sim no)
		(in_bom yes)
		(on_board yes)
		(dnp no)
		(fields_autoplaced yes)
		(property "Reference" "U2"
			(at 74.93 249.5549 90)
			(effects
				(font
					(size 1.27 1.27)
				)
				(justify left)
			)
		)
		(property "Value" "TPD4E05U06QDQARQ1"
			(at 74.93 252.0949 90)
			(effects
				(font
					(size 1.27 1.27)
					(thickness 0.15)
				)
				(justify left)
			)
		)
		(property "Footprint" "antmicro-footprints:USON-10_2.5x1mm_P0.5mm"
			(at 66.04 269.24 0)
			(effects
				(font
					(size 1.27 1.27)
					(thickness 0.15)
				)
				(justify left bottom)
				(hide yes)
			)
		)
		(property "Datasheet" "https://www.ti.com/lit/ds/symlink/tpd4e05u06-q1.pdf?HQS=dis-mous-null-mousermode-dsf-pf-null-wwe&ts=1663591265741&ref_url=https%253A%252F%252Fwww.mouser.com%252F"
			(at 63.5 269.24 0)
			(effects
				(font
					(size 1.27 1.27)
					(thickness 0.15)
				)
				(justify left bottom)
				(hide yes)
			)
		)
		(property "Description" ""
			(at 71.12 245.11 0)
			(effects
				(font
					(size 1.27 1.27)
				)
			)
		)
		(property "Manufacturer" "Texas Instruments"
			(at 60.96 269.24 0)
			(effects
				(font
					(size 1.27 1.27)
					(thickness 0.15)
				)
				(justify left bottom)
				(hide yes)
			)
		)
		(property "MPN" "TPD4E05U06QDQARQ1"
			(at 58.42 269.24 0)
			(effects
				(font
					(size 1.27 1.27)
					(thickness 0.15)
				)
				(justify left bottom)
				(hide yes)
			)
		)
		(property "Author" "Antmicro"
			(at 55.88 269.24 0)
			(effects
				(font
					(size 1.27 1.27)
					(thickness 0.15)
				)
				(justify left bottom)
				(hide yes)
			)
		)
		(property "License" "Apache-2.0"
			(at 53.34 269.24 0)
			(effects
				(font
					(size 1.27 1.27)
					(thickness 0.15)
				)
				(justify left bottom)
				(hide yes)
			)
		)
		(pin "1"
		)
		(pin "10"
		)
		(pin "2"
		)
		(pin "3"
		)
		(pin "4"
		)
		(pin "5"
		)
		(pin "6"
		)
		(pin "7"
		)
		(pin "8"
		)
		(pin "9"
		)
		(instances
			(project "k410t-devboard"
				(path ""
					(reference "U2")
					(unit 1)
				)
			)
		)
	)
	(symbol
		(lib_id "antmicroResistors0402:R_10k_0402")
		(at 248.92 120.65 90)
		(unit 1)
		(exclude_from_sim no)
		(in_bom yes)
		(on_board yes)
		(dnp no)
		(property "Reference" "R6"
			(at 250.19 116.84 90)
			(effects
				(font
					(size 1.27 1.27)
				)
				(justify right)
			)
		)
		(property "Value" "R_10k_0402"
			(at 261.62 100.33 0)
			(effects
				(font
					(size 1.27 1.27)
					(thickness 0.15)
				)
				(justify left bottom)
				(hide yes)
			)
		)
		(property "Footprint" "antmicro-footprints:R_0402_1005Metric"
			(at 264.16 100.33 0)
			(effects
				(font
					(size 1.27 1.27)
					(thickness 0.15)
				)
				(justify left bottom)
				(hide yes)
			)
		)
		(property "Datasheet" "https://www.bourns.com/docs/product-datasheets/cr.pdf"
			(at 266.7 100.33 0)
			(effects
				(font
					(size 1.27 1.27)
					(thickness 0.15)
				)
				(justify left bottom)
				(hide yes)
			)
		)
		(property "Description" ""
			(at 248.92 120.65 0)
			(effects
				(font
					(size 1.27 1.27)
				)
			)
		)
		(property "Manufacturer" "Bourns"
			(at 271.78 100.33 0)
			(effects
				(font
					(size 1.27 1.27)
					(thickness 0.15)
				)
				(justify left bottom)
				(hide yes)
			)
		)
		(property "MPN" "CR0402-FX-1002GLF"
			(at 269.24 100.33 0)
			(effects
				(font
					(size 1.27 1.27)
					(thickness 0.15)
				)
				(justify left bottom)
				(hide yes)
			)
		)
		(property "Val" "10k"
			(at 250.19 119.38 90)
			(effects
				(font
					(size 1.27 1.27)
					(thickness 0.15)
				)
				(justify right)
			)
		)
		(property "License" "Apache-2.0"
			(at 274.32 100.33 0)
			(effects
				(font
					(size 1.27 1.27)
					(thickness 0.15)
				)
				(justify left bottom)
				(hide yes)
			)
		)
		(property "Author" "Antmicro"
			(at 276.86 100.33 0)
			(effects
				(font
					(size 1.27 1.27)
					(thickness 0.15)
				)
				(justify left bottom)
				(hide yes)
			)
		)
		(property "Tolerance" "1%"
			(at 259.08 100.33 0)
			(effects
				(font
					(size 1.27 1.27)
				)
				(justify left bottom)
				(hide yes)
			)
		)
		(pin "1"
		)
		(pin "2"
		)
		(instances
			(project "k410t-devboard"
				(path ""
					(reference "R6")
					(unit 1)
				)
			)
		)
	)
	(symbol
		(lib_id "k410t-devboard:Net-Tie_2")
		(at 180.34 106.68 0)
		(mirror x)
		(unit 1)
		(exclude_from_sim no)
		(in_bom yes)
		(on_board yes)
		(dnp no)
		(fields_autoplaced yes)
		(property "Reference" "NT5"
			(at 180.34 107.95 0)
			(effects
				(font
					(size 1.27 1.27)
				)
				(hide yes)
			)
		)
		(property "Value" "Net-Tie_2"
			(at 201.93 104.14 0)
			(effects
				(font
					(size 1.27 1.27)
					(thickness 0.15)
				)
				(justify left bottom)
				(hide yes)
			)
		)
		(property "Footprint" "antmicro-footprints:NetTie-2_SMD_Pad0.127mm"
			(at 201.93 101.6 0)
			(effects
				(font
					(size 1.27 1.27)
					(thickness 0.15)
				)
				(justify left bottom)
				(hide yes)
			)
		)
		(property "Datasheet" ""
			(at 201.93 99.06 0)
			(effects
				(font
					(size 1.27 1.27)
					(thickness 0.15)
				)
				(justify left bottom)
				(hide yes)
			)
		)
		(property "Description" ""
			(at 180.34 106.68 0)
			(effects
				(font
					(size 1.27 1.27)
				)
			)
		)
		(property "MPN" ""
			(at 201.93 97.79 0)
			(effects
				(font
					(size 1.27 1.27)
				)
				(justify left)
				(hide yes)
			)
		)
		(property "Manufacturer" ""
			(at 201.93 95.25 0)
			(effects
				(font
					(size 1.27 1.27)
				)
				(justify left)
				(hide yes)
			)
		)
		(property "Author" "Antmicro"
			(at 201.93 91.44 0)
			(effects
				(font
					(size 1.27 1.27)
					(thickness 0.15)
				)
				(justify left bottom)
				(hide yes)
			)
		)
		(property "License" "Apache-2.0"
			(at 201.93 88.9 0)
			(effects
				(font
					(size 1.27 1.27)
					(thickness 0.15)
				)
				(justify left bottom)
				(hide yes)
			)
		)
		(pin "1"
		)
		(pin "2"
		)
		(instances
			(project "k410t-devboard"
				(path ""
					(reference "NT5")
					(unit 1)
				)
			)
		)
	)
	(symbol
		(lib_id "antmicropower:+3.3V")
		(at 355.6 176.53 0)
		(unit 1)
		(exclude_from_sim no)
		(in_bom yes)
		(on_board yes)
		(dnp no)
		(fields_autoplaced yes)
		(property "Reference" "#PWR058"
			(at 355.6 180.34 0)
			(effects
				(font
					(size 1.27 1.27)
				)
				(hide yes)
			)
		)
		(property "Value" "+3V3"
			(at 355.6 172.974 0)
			(effects
				(font
					(size 1.27 1.27)
				)
			)
		)
		(property "Footprint" ""
			(at 355.6 176.53 0)
			(effects
				(font
					(size 1.27 1.27)
				)
				(hide yes)
			)
		)
		(property "Datasheet" ""
			(at 355.6 176.53 0)
			(effects
				(font
					(size 1.27 1.27)
				)
				(hide yes)
			)
		)
		(property "Description" ""
			(at 355.6 176.53 0)
			(effects
				(font
					(size 1.27 1.27)
				)
			)
		)
		(pin "1"
		)
		(instances
			(project "k410t-devboard"
				(path ""
					(reference "#PWR058")
					(unit 1)
				)
			)
		)
	)
	(symbol
		(lib_id "antmicropower:+3.3V")
		(at 238.76 113.03 0)
		(unit 1)
		(exclude_from_sim no)
		(in_bom yes)
		(on_board yes)
		(dnp no)
		(fields_autoplaced yes)
		(property "Reference" "#PWR048"
			(at 238.76 116.84 0)
			(effects
				(font
					(size 1.27 1.27)
				)
				(hide yes)
			)
		)
		(property "Value" "+3V3"
			(at 238.76 109.474 0)
			(effects
				(font
					(size 1.27 1.27)
				)
			)
		)
		(property "Footprint" ""
			(at 238.76 113.03 0)
			(effects
				(font
					(size 1.27 1.27)
				)
				(hide yes)
			)
		)
		(property "Datasheet" ""
			(at 238.76 113.03 0)
			(effects
				(font
					(size 1.27 1.27)
				)
				(hide yes)
			)
		)
		(property "Description" ""
			(at 238.76 113.03 0)
			(effects
				(font
					(size 1.27 1.27)
				)
			)
		)
		(pin "1"
		)
		(instances
			(project "k410t-devboard"
				(path ""
					(reference "#PWR048")
					(unit 1)
				)
			)
		)
	)
	(symbol
		(lib_id "k410t-devboard:Net-Tie_2")
		(at 274.32 105.41 0)
		(mirror x)
		(unit 1)
		(exclude_from_sim no)
		(in_bom yes)
		(on_board yes)
		(dnp no)
		(fields_autoplaced yes)
		(property "Reference" "NT6"
			(at 274.32 106.68 0)
			(effects
				(font
					(size 1.27 1.27)
				)
				(hide yes)
			)
		)
		(property "Value" "Net-Tie_2"
			(at 295.91 102.87 0)
			(effects
				(font
					(size 1.27 1.27)
					(thickness 0.15)
				)
				(justify left bottom)
				(hide yes)
			)
		)
		(property "Footprint" "antmicro-footprints:NetTie-2_SMD_Pad0.127mm"
			(at 295.91 100.33 0)
			(effects
				(font
					(size 1.27 1.27)
					(thickness 0.15)
				)
				(justify left bottom)
				(hide yes)
			)
		)
		(property "Datasheet" ""
			(at 295.91 97.79 0)
			(effects
				(font
					(size 1.27 1.27)
					(thickness 0.15)
				)
				(justify left bottom)
				(hide yes)
			)
		)
		(property "Description" ""
			(at 274.32 105.41 0)
			(effects
				(font
					(size 1.27 1.27)
				)
			)
		)
		(property "MPN" ""
			(at 295.91 96.52 0)
			(effects
				(font
					(size 1.27 1.27)
				)
				(justify left)
				(hide yes)
			)
		)
		(property "Manufacturer" ""
			(at 295.91 93.98 0)
			(effects
				(font
					(size 1.27 1.27)
				)
				(justify left)
				(hide yes)
			)
		)
		(property "Author" "Antmicro"
			(at 295.91 90.17 0)
			(effects
				(font
					(size 1.27 1.27)
					(thickness 0.15)
				)
				(justify left bottom)
				(hide yes)
			)
		)
		(property "License" "Apache-2.0"
			(at 295.91 87.63 0)
			(effects
				(font
					(size 1.27 1.27)
					(thickness 0.15)
				)
				(justify left bottom)
				(hide yes)
			)
		)
		(pin "1"
		)
		(pin "2"
		)
		(instances
			(project "k410t-devboard"
				(path ""
					(reference "NT6")
					(unit 1)
				)
			)
		)
	)
	(symbol
		(lib_id "k410t-devboard:Net-Tie_2")
		(at 274.32 100.33 0)
		(mirror x)
		(unit 1)
		(exclude_from_sim no)
		(in_bom yes)
		(on_board yes)
		(dnp no)
		(fields_autoplaced yes)
		(property "Reference" "NT8"
			(at 274.32 101.6 0)
			(effects
				(font
					(size 1.27 1.27)
				)
				(hide yes)
			)
		)
		(property "Value" "Net-Tie_2"
			(at 295.91 97.79 0)
			(effects
				(font
					(size 1.27 1.27)
					(thickness 0.15)
				)
				(justify left bottom)
				(hide yes)
			)
		)
		(property "Footprint" "antmicro-footprints:NetTie-2_SMD_Pad0.127mm"
			(at 295.91 95.25 0)
			(effects
				(font
					(size 1.27 1.27)
					(thickness 0.15)
				)
				(justify left bottom)
				(hide yes)
			)
		)
		(property "Datasheet" ""
			(at 295.91 92.71 0)
			(effects
				(font
					(size 1.27 1.27)
					(thickness 0.15)
				)
				(justify left bottom)
				(hide yes)
			)
		)
		(property "Description" ""
			(at 274.32 100.33 0)
			(effects
				(font
					(size 1.27 1.27)
				)
			)
		)
		(property "MPN" ""
			(at 295.91 91.44 0)
			(effects
				(font
					(size 1.27 1.27)
				)
				(justify left)
				(hide yes)
			)
		)
		(property "Manufacturer" ""
			(at 295.91 88.9 0)
			(effects
				(font
					(size 1.27 1.27)
				)
				(justify left)
				(hide yes)
			)
		)
		(property "Author" "Antmicro"
			(at 295.91 85.09 0)
			(effects
				(font
					(size 1.27 1.27)
					(thickness 0.15)
				)
				(justify left bottom)
				(hide yes)
			)
		)
		(property "License" "Apache-2.0"
			(at 295.91 82.55 0)
			(effects
				(font
					(size 1.27 1.27)
					(thickness 0.15)
				)
				(justify left bottom)
				(hide yes)
			)
		)
		(pin "1"
		)
		(pin "2"
		)
		(instances
			(project "k410t-devboard"
				(path ""
					(reference "NT8")
					(unit 1)
				)
			)
		)
	)
	(symbol
		(lib_id "antmicroCapacitors0402:C_100n_0402")
		(at 299.72 171.45 90)
		(unit 1)
		(exclude_from_sim no)
		(in_bom yes)
		(on_board yes)
		(dnp no)
		(property "Reference" "C164"
			(at 300.355 167.005 90)
			(effects
				(font
					(size 1.27 1.27)
				)
				(justify right)
			)
		)
		(property "Value" "C_100n_0402"
			(at 309.88 151.13 0)
			(effects
				(font
					(size 1.27 1.27)
					(thickness 0.15)
				)
				(justify left bottom)
				(hide yes)
			)
		)
		(property "Footprint" "antmicro-footprints:C_0402_1005Metric"
			(at 312.42 151.13 0)
			(effects
				(font
					(size 1.27 1.27)
					(thickness 0.15)
				)
				(justify left bottom)
				(hide yes)
			)
		)
		(property "Datasheet" "https://www.murata.com/products/productdetail?partno=GRM155R61H104KE14%23"
			(at 314.96 151.13 0)
			(effects
				(font
					(size 1.27 1.27)
					(thickness 0.15)
				)
				(justify left bottom)
				(hide yes)
			)
		)
		(property "Description" ""
			(at 299.72 171.45 0)
			(effects
				(font
					(size 1.27 1.27)
				)
			)
		)
		(property "Manufacturer" "Murata"
			(at 320.04 151.13 0)
			(effects
				(font
					(size 1.27 1.27)
					(thickness 0.15)
				)
				(justify left bottom)
				(hide yes)
			)
		)
		(property "MPN" "GRM155R61H104KE14D"
			(at 317.5 151.13 0)
			(effects
				(font
					(size 1.27 1.27)
					(thickness 0.15)
				)
				(justify left bottom)
				(hide yes)
			)
		)
		(property "Val" "100n"
			(at 300.355 170.815 90)
			(effects
				(font
					(size 1.27 1.27)
					(thickness 0.15)
				)
				(justify right)
			)
		)
		(property "License" "Apache-2.0"
			(at 322.58 151.13 0)
			(effects
				(font
					(size 1.27 1.27)
					(thickness 0.15)
				)
				(justify left bottom)
				(hide yes)
			)
		)
		(property "Author" "Antmicro"
			(at 325.12 151.13 0)
			(effects
				(font
					(size 1.27 1.27)
					(thickness 0.15)
				)
				(justify left bottom)
				(hide yes)
			)
		)
		(property "Voltage" "50V"
			(at 327.66 151.13 0)
			(effects
				(font
					(size 1.27 1.27)
				)
				(justify left bottom)
				(hide yes)
			)
		)
		(property "Dielectric" "X5R"
			(at 330.2 151.13 0)
			(effects
				(font
					(size 1.27 1.27)
				)
				(justify left bottom)
				(hide yes)
			)
		)
		(pin "1"
		)
		(pin "2"
		)
		(instances
			(project "k410t-devboard"
				(path ""
					(reference "C164")
					(unit 1)
				)
			)
		)
	)
	(symbol
		(lib_id "antmicroGenericPinHeaders:PinHeader_2x7_P2mm_SMD_Shrouded_no-locator")
		(at 39.37 222.25 0)
		(unit 1)
		(exclude_from_sim no)
		(in_bom yes)
		(on_board yes)
		(dnp no)
		(property "Reference" "J1"
			(at 44.45 216.535 0)
			(effects
				(font
					(size 1.27 1.27)
					(thickness 0.15)
				)
			)
		)
		(property "Value" "PinHeader_2x7_P2mm_SMD_Shrouded_no-locator"
			(at 64.77 227.33 0)
			(effects
				(font
					(size 1.27 1.27)
					(thickness 0.15)
				)
				(justify left bottom)
				(hide yes)
			)
		)
		(property "Footprint" "antmicro-footprints:PinHeader_2x7_P2mm_SMD_Shrouded_no-locator"
			(at 64.77 229.87 0)
			(effects
				(font
					(size 1.27 1.27)
					(thickness 0.15)
				)
				(justify left bottom)
				(hide yes)
			)
		)
		(property "Datasheet" "https://www.molex.com/pdm_docs/ps/PS-87831-027-001.pdf"
			(at 64.77 232.41 0)
			(effects
				(font
					(size 1.27 1.27)
					(thickness 0.15)
				)
				(justify left bottom)
				(hide yes)
			)
		)
		(property "Description" ""
			(at 39.37 222.25 0)
			(effects
				(font
					(size 1.27 1.27)
				)
			)
		)
		(property "MPN" "878321412"
			(at 44.45 219.075 0)
			(effects
				(font
					(size 1.27 1.27)
					(thickness 0.15)
				)
			)
		)
		(property "Manufacturer" "Molex"
			(at 64.77 237.49 0)
			(effects
				(font
					(size 1.27 1.27)
					(thickness 0.15)
				)
				(justify left bottom)
				(hide yes)
			)
		)
		(property "Author" "Antmicro"
			(at 64.77 240.03 0)
			(effects
				(font
					(size 1.27 1.27)
					(thickness 0.15)
				)
				(justify left bottom)
				(hide yes)
			)
		)
		(property "License" "Apache-2.0"
			(at 64.77 242.57 0)
			(effects
				(font
					(size 1.27 1.27)
					(thickness 0.15)
				)
				(justify left bottom)
				(hide yes)
			)
		)
		(pin "1"
		)
		(pin "10"
		)
		(pin "11"
		)
		(pin "12"
		)
		(pin "13"
		)
		(pin "14"
		)
		(pin "2"
		)
		(pin "3"
		)
		(pin "4"
		)
		(pin "5"
		)
		(pin "6"
		)
		(pin "7"
		)
		(pin "8"
		)
		(pin "9"
		)
		(instances
			(project "k410t-devboard"
				(path ""
					(reference "J1")
					(unit 1)
				)
			)
		)
	)
	(symbol
		(lib_id "k410t-devboard:Net-Tie_2")
		(at 180.34 109.22 0)
		(mirror x)
		(unit 1)
		(exclude_from_sim no)
		(in_bom yes)
		(on_board yes)
		(dnp no)
		(fields_autoplaced yes)
		(property "Reference" "NT4"
			(at 180.34 110.49 0)
			(effects
				(font
					(size 1.27 1.27)
				)
				(hide yes)
			)
		)
		(property "Value" "Net-Tie_2"
			(at 201.93 106.68 0)
			(effects
				(font
					(size 1.27 1.27)
					(thickness 0.15)
				)
				(justify left bottom)
				(hide yes)
			)
		)
		(property "Footprint" "antmicro-footprints:NetTie-2_SMD_Pad0.127mm"
			(at 201.93 104.14 0)
			(effects
				(font
					(size 1.27 1.27)
					(thickness 0.15)
				)
				(justify left bottom)
				(hide yes)
			)
		)
		(property "Datasheet" ""
			(at 201.93 101.6 0)
			(effects
				(font
					(size 1.27 1.27)
					(thickness 0.15)
				)
				(justify left bottom)
				(hide yes)
			)
		)
		(property "Description" ""
			(at 180.34 109.22 0)
			(effects
				(font
					(size 1.27 1.27)
				)
			)
		)
		(property "MPN" ""
			(at 201.93 100.33 0)
			(effects
				(font
					(size 1.27 1.27)
				)
				(justify left)
				(hide yes)
			)
		)
		(property "Manufacturer" ""
			(at 201.93 97.79 0)
			(effects
				(font
					(size 1.27 1.27)
				)
				(justify left)
				(hide yes)
			)
		)
		(property "Author" "Antmicro"
			(at 201.93 93.98 0)
			(effects
				(font
					(size 1.27 1.27)
					(thickness 0.15)
				)
				(justify left bottom)
				(hide yes)
			)
		)
		(property "License" "Apache-2.0"
			(at 201.93 91.44 0)
			(effects
				(font
					(size 1.27 1.27)
					(thickness 0.15)
				)
				(justify left bottom)
				(hide yes)
			)
		)
		(pin "1"
		)
		(pin "2"
		)
		(instances
			(project "k410t-devboard"
				(path ""
					(reference "NT4")
					(unit 1)
				)
			)
		)
	)
	(symbol
		(lib_id "antmicropower:GND")
		(at 261.62 147.32 0)
		(unit 1)
		(exclude_from_sim no)
		(in_bom yes)
		(on_board yes)
		(dnp no)
		(property "Reference" "#PWR046"
			(at 261.62 153.67 0)
			(effects
				(font
					(size 1.27 1.27)
				)
				(hide yes)
			)
		)
		(property "Value" "GND"
			(at 261.62 151.13 0)
			(effects
				(font
					(size 1.27 1.27)
				)
			)
		)
		(property "Footprint" ""
			(at 270.51 154.94 0)
			(effects
				(font
					(size 1.27 1.27)
					(thickness 0.15)
				)
				(justify left bottom)
				(hide yes)
			)
		)
		(property "Datasheet" ""
			(at 270.51 160.02 0)
			(effects
				(font
					(size 1.27 1.27)
					(thickness 0.15)
				)
				(justify left bottom)
				(hide yes)
			)
		)
		(property "Description" ""
			(at 261.62 147.32 0)
			(effects
				(font
					(size 1.27 1.27)
				)
			)
		)
		(property "Author" "Antmicro"
			(at 270.51 154.94 0)
			(effects
				(font
					(size 1.27 1.27)
					(thickness 0.15)
				)
				(justify left bottom)
				(hide yes)
			)
		)
		(property "License" "Apache-2.0"
			(at 270.51 157.48 0)
			(effects
				(font
					(size 1.27 1.27)
					(thickness 0.15)
				)
				(justify left bottom)
				(hide yes)
			)
		)
		(pin "1"
		)
		(instances
			(project "k410t-devboard"
				(path ""
					(reference "#PWR046")
					(unit 1)
				)
			)
		)
	)
	(symbol
		(lib_id "k410t-devboard:Net-Tie_2")
		(at 267.97 146.05 180)
		(unit 1)
		(exclude_from_sim no)
		(in_bom yes)
		(on_board yes)
		(dnp no)
		(fields_autoplaced yes)
		(property "Reference" "NT24"
			(at 267.97 147.32 0)
			(effects
				(font
					(size 1.27 1.27)
				)
				(hide yes)
			)
		)
		(property "Value" "Net-Tie_2"
			(at 246.38 143.51 0)
			(effects
				(font
					(size 1.27 1.27)
					(thickness 0.15)
				)
				(justify left bottom)
				(hide yes)
			)
		)
		(property "Footprint" "antmicro-footprints:NetTie-2_SMD_Pad0.127mm"
			(at 246.38 140.97 0)
			(effects
				(font
					(size 1.27 1.27)
					(thickness 0.15)
				)
				(justify left bottom)
				(hide yes)
			)
		)
		(property "Datasheet" ""
			(at 246.38 138.43 0)
			(effects
				(font
					(size 1.27 1.27)
					(thickness 0.15)
				)
				(justify left bottom)
				(hide yes)
			)
		)
		(property "Description" ""
			(at 267.97 146.05 0)
			(effects
				(font
					(size 1.27 1.27)
				)
			)
		)
		(property "MPN" ""
			(at 246.38 137.16 0)
			(effects
				(font
					(size 1.27 1.27)
				)
				(justify left)
				(hide yes)
			)
		)
		(property "Manufacturer" ""
			(at 246.38 134.62 0)
			(effects
				(font
					(size 1.27 1.27)
				)
				(justify left)
				(hide yes)
			)
		)
		(property "Author" "Antmicro"
			(at 246.38 130.81 0)
			(effects
				(font
					(size 1.27 1.27)
					(thickness 0.15)
				)
				(justify left bottom)
				(hide yes)
			)
		)
		(property "License" "Apache-2.0"
			(at 246.38 128.27 0)
			(effects
				(font
					(size 1.27 1.27)
					(thickness 0.15)
				)
				(justify left bottom)
				(hide yes)
			)
		)
		(pin "1"
		)
		(pin "2"
		)
		(instances
			(project "k410t-devboard"
				(path ""
					(reference "NT24")
					(unit 1)
				)
			)
		)
	)
	(symbol
		(lib_id "k410t-devboard:Net-Tie_2")
		(at 350.52 195.58 270)
		(mirror x)
		(unit 1)
		(exclude_from_sim no)
		(in_bom yes)
		(on_board yes)
		(dnp no)
		(fields_autoplaced yes)
		(property "Reference" "NT21"
			(at 351.79 195.58 0)
			(effects
				(font
					(size 1.27 1.27)
				)
				(hide yes)
			)
		)
		(property "Value" "Net-Tie_2"
			(at 347.98 173.99 0)
			(effects
				(font
					(size 1.27 1.27)
					(thickness 0.15)
				)
				(justify left bottom)
				(hide yes)
			)
		)
		(property "Footprint" "antmicro-footprints:NetTie-2_SMD_Pad0.127mm"
			(at 345.44 173.99 0)
			(effects
				(font
					(size 1.27 1.27)
					(thickness 0.15)
				)
				(justify left bottom)
				(hide yes)
			)
		)
		(property "Datasheet" ""
			(at 342.9 173.99 0)
			(effects
				(font
					(size 1.27 1.27)
					(thickness 0.15)
				)
				(justify left bottom)
				(hide yes)
			)
		)
		(property "Description" ""
			(at 350.52 195.58 0)
			(effects
				(font
					(size 1.27 1.27)
				)
			)
		)
		(property "MPN" ""
			(at 341.63 173.99 0)
			(effects
				(font
					(size 1.27 1.27)
				)
				(justify left)
				(hide yes)
			)
		)
		(property "Manufacturer" ""
			(at 339.09 173.99 0)
			(effects
				(font
					(size 1.27 1.27)
				)
				(justify left)
				(hide yes)
			)
		)
		(property "Author" "Antmicro"
			(at 335.28 173.99 0)
			(effects
				(font
					(size 1.27 1.27)
					(thickness 0.15)
				)
				(justify left bottom)
				(hide yes)
			)
		)
		(property "License" "Apache-2.0"
			(at 332.74 173.99 0)
			(effects
				(font
					(size 1.27 1.27)
					(thickness 0.15)
				)
				(justify left bottom)
				(hide yes)
			)
		)
		(pin "1"
		)
		(pin "2"
		)
		(instances
			(project "k410t-devboard"
				(path ""
					(reference "NT21")
					(unit 1)
				)
			)
		)
	)
	(symbol
		(lib_id "k410t-devboard:Net-Tie_2")
		(at 274.32 102.87 0)
		(mirror x)
		(unit 1)
		(exclude_from_sim no)
		(in_bom yes)
		(on_board yes)
		(dnp no)
		(fields_autoplaced yes)
		(property "Reference" "NT7"
			(at 274.32 104.14 0)
			(effects
				(font
					(size 1.27 1.27)
				)
				(hide yes)
			)
		)
		(property "Value" "Net-Tie_2"
			(at 295.91 100.33 0)
			(effects
				(font
					(size 1.27 1.27)
					(thickness 0.15)
				)
				(justify left bottom)
				(hide yes)
			)
		)
		(property "Footprint" "antmicro-footprints:NetTie-2_SMD_Pad0.127mm"
			(at 295.91 97.79 0)
			(effects
				(font
					(size 1.27 1.27)
					(thickness 0.15)
				)
				(justify left bottom)
				(hide yes)
			)
		)
		(property "Datasheet" ""
			(at 295.91 95.25 0)
			(effects
				(font
					(size 1.27 1.27)
					(thickness 0.15)
				)
				(justify left bottom)
				(hide yes)
			)
		)
		(property "Description" ""
			(at 274.32 102.87 0)
			(effects
				(font
					(size 1.27 1.27)
				)
			)
		)
		(property "MPN" ""
			(at 295.91 93.98 0)
			(effects
				(font
					(size 1.27 1.27)
				)
				(justify left)
				(hide yes)
			)
		)
		(property "Manufacturer" ""
			(at 295.91 91.44 0)
			(effects
				(font
					(size 1.27 1.27)
				)
				(justify left)
				(hide yes)
			)
		)
		(property "Author" "Antmicro"
			(at 295.91 87.63 0)
			(effects
				(font
					(size 1.27 1.27)
					(thickness 0.15)
				)
				(justify left bottom)
				(hide yes)
			)
		)
		(property "License" "Apache-2.0"
			(at 295.91 85.09 0)
			(effects
				(font
					(size 1.27 1.27)
					(thickness 0.15)
				)
				(justify left bottom)
				(hide yes)
			)
		)
		(pin "1"
		)
		(pin "2"
		)
		(instances
			(project "k410t-devboard"
				(path ""
					(reference "NT7")
					(unit 1)
				)
			)
		)
	)
	(symbol
		(lib_id "antmicropower:GND")
		(at 173.99 80.01 0)
		(unit 1)
		(exclude_from_sim no)
		(in_bom yes)
		(on_board yes)
		(dnp no)
		(property "Reference" "#PWR018"
			(at 173.99 86.36 0)
			(effects
				(font
					(size 1.27 1.27)
				)
				(hide yes)
			)
		)
		(property "Value" "GND"
			(at 173.99 83.82 0)
			(effects
				(font
					(size 1.27 1.27)
				)
			)
		)
		(property "Footprint" ""
			(at 182.88 87.63 0)
			(effects
				(font
					(size 1.27 1.27)
					(thickness 0.15)
				)
				(justify left bottom)
				(hide yes)
			)
		)
		(property "Datasheet" ""
			(at 182.88 92.71 0)
			(effects
				(font
					(size 1.27 1.27)
					(thickness 0.15)
				)
				(justify left bottom)
				(hide yes)
			)
		)
		(property "Description" ""
			(at 173.99 80.01 0)
			(effects
				(font
					(size 1.27 1.27)
				)
			)
		)
		(property "Author" "Antmicro"
			(at 182.88 87.63 0)
			(effects
				(font
					(size 1.27 1.27)
					(thickness 0.15)
				)
				(justify left bottom)
				(hide yes)
			)
		)
		(property "License" "Apache-2.0"
			(at 182.88 90.17 0)
			(effects
				(font
					(size 1.27 1.27)
					(thickness 0.15)
				)
				(justify left bottom)
				(hide yes)
			)
		)
		(pin "1"
		)
		(instances
			(project "k410t-devboard"
				(path ""
					(reference "#PWR018")
					(unit 1)
				)
			)
		)
	)
	(symbol
		(lib_id "antmicroCapacitors0402:C_100n_0402")
		(at 181.61 76.2 90)
		(unit 1)
		(exclude_from_sim no)
		(in_bom yes)
		(on_board yes)
		(dnp no)
		(property "Reference" "C10"
			(at 182.245 71.755 90)
			(effects
				(font
					(size 1.27 1.27)
				)
				(justify right)
			)
		)
		(property "Value" "C_100n_0402"
			(at 191.77 55.88 0)
			(effects
				(font
					(size 1.27 1.27)
					(thickness 0.15)
				)
				(justify left bottom)
				(hide yes)
			)
		)
		(property "Footprint" "antmicro-footprints:C_0402_1005Metric"
			(at 194.31 55.88 0)
			(effects
				(font
					(size 1.27 1.27)
					(thickness 0.15)
				)
				(justify left bottom)
				(hide yes)
			)
		)
		(property "Datasheet" "https://www.murata.com/products/productdetail?partno=GRM155R61H104KE14%23"
			(at 196.85 55.88 0)
			(effects
				(font
					(size 1.27 1.27)
					(thickness 0.15)
				)
				(justify left bottom)
				(hide yes)
			)
		)
		(property "Description" ""
			(at 181.61 76.2 0)
			(effects
				(font
					(size 1.27 1.27)
				)
			)
		)
		(property "Manufacturer" "Murata"
			(at 201.93 55.88 0)
			(effects
				(font
					(size 1.27 1.27)
					(thickness 0.15)
				)
				(justify left bottom)
				(hide yes)
			)
		)
		(property "MPN" "GRM155R61H104KE14D"
			(at 199.39 55.88 0)
			(effects
				(font
					(size 1.27 1.27)
					(thickness 0.15)
				)
				(justify left bottom)
				(hide yes)
			)
		)
		(property "Val" "100n"
			(at 182.245 75.565 90)
			(effects
				(font
					(size 1.27 1.27)
					(thickness 0.15)
				)
				(justify right)
			)
		)
		(property "License" "Apache-2.0"
			(at 204.47 55.88 0)
			(effects
				(font
					(size 1.27 1.27)
					(thickness 0.15)
				)
				(justify left bottom)
				(hide yes)
			)
		)
		(property "Author" "Antmicro"
			(at 207.01 55.88 0)
			(effects
				(font
					(size 1.27 1.27)
					(thickness 0.15)
				)
				(justify left bottom)
				(hide yes)
			)
		)
		(property "Voltage" "50V"
			(at 209.55 55.88 0)
			(effects
				(font
					(size 1.27 1.27)
				)
				(justify left bottom)
				(hide yes)
			)
		)
		(property "Dielectric" "X5R"
			(at 212.09 55.88 0)
			(effects
				(font
					(size 1.27 1.27)
				)
				(justify left bottom)
				(hide yes)
			)
		)
		(pin "1"
		)
		(pin "2"
		)
		(instances
			(project "k410t-devboard"
				(path ""
					(reference "C10")
					(unit 1)
				)
			)
		)
	)
	(symbol
		(lib_id "antmicroResistors0402:R_10k_0402")
		(at 118.11 121.92 90)
		(mirror x)
		(unit 1)
		(exclude_from_sim no)
		(in_bom no)
		(on_board yes)
		(dnp yes)
		(property "Reference" "R3"
			(at 119.38 123.19 90)
			(effects
				(font
					(size 1.27 1.27)
				)
				(justify right)
			)
		)
		(property "Value" "R_10k_0402"
			(at 130.81 142.24 0)
			(effects
				(font
					(size 1.27 1.27)
					(thickness 0.15)
				)
				(justify left bottom)
				(hide yes)
			)
		)
		(property "Footprint" "antmicro-footprints:R_0402_1005Metric"
			(at 133.35 142.24 0)
			(effects
				(font
					(size 1.27 1.27)
					(thickness 0.15)
				)
				(justify left bottom)
				(hide yes)
			)
		)
		(property "Datasheet" "https://www.bourns.com/docs/product-datasheets/cr.pdf"
			(at 135.89 142.24 0)
			(effects
				(font
					(size 1.27 1.27)
					(thickness 0.15)
				)
				(justify left bottom)
				(hide yes)
			)
		)
		(property "Description" ""
			(at 118.11 121.92 0)
			(effects
				(font
					(size 1.27 1.27)
				)
			)
		)
		(property "Manufacturer" "Bourns"
			(at 140.97 142.24 0)
			(effects
				(font
					(size 1.27 1.27)
					(thickness 0.15)
				)
				(justify left bottom)
				(hide yes)
			)
		)
		(property "MPN" "CR0402-FX-1002GLF"
			(at 138.43 142.24 0)
			(effects
				(font
					(size 1.27 1.27)
					(thickness 0.15)
				)
				(justify left bottom)
				(hide yes)
			)
		)
		(property "Val" "10k"
			(at 119.38 125.73 90)
			(effects
				(font
					(size 1.27 1.27)
					(thickness 0.15)
				)
				(justify right)
			)
		)
		(property "DNP" "DNP"
			(at 118.11 126.365 0)
			(effects
				(font
					(size 1.27 1.27)
				)
				(justify right)
			)
		)
		(property "License" "Apache-2.0"
			(at 143.51 142.24 0)
			(effects
				(font
					(size 1.27 1.27)
					(thickness 0.15)
				)
				(justify left bottom)
				(hide yes)
			)
		)
		(property "Author" "Antmicro"
			(at 146.05 142.24 0)
			(effects
				(font
					(size 1.27 1.27)
					(thickness 0.15)
				)
				(justify left bottom)
				(hide yes)
			)
		)
		(property "Tolerance" "1%"
			(at 128.27 142.24 0)
			(effects
				(font
					(size 1.27 1.27)
				)
				(justify left bottom)
				(hide yes)
			)
		)
		(pin "1"
		)
		(pin "2"
		)
		(instances
			(project "k410t-devboard"
				(path ""
					(reference "R3")
					(unit 1)
				)
			)
		)
	)
	(symbol
		(lib_id "antmicroCapacitors0402:C_100n_0402")
		(at 189.23 76.2 90)
		(unit 1)
		(exclude_from_sim no)
		(in_bom yes)
		(on_board yes)
		(dnp no)
		(property "Reference" "C16"
			(at 189.865 71.755 90)
			(effects
				(font
					(size 1.27 1.27)
				)
				(justify right)
			)
		)
		(property "Value" "C_100n_0402"
			(at 199.39 55.88 0)
			(effects
				(font
					(size 1.27 1.27)
					(thickness 0.15)
				)
				(justify left bottom)
				(hide yes)
			)
		)
		(property "Footprint" "antmicro-footprints:C_0402_1005Metric"
			(at 201.93 55.88 0)
			(effects
				(font
					(size 1.27 1.27)
					(thickness 0.15)
				)
				(justify left bottom)
				(hide yes)
			)
		)
		(property "Datasheet" "https://www.murata.com/products/productdetail?partno=GRM155R61H104KE14%23"
			(at 204.47 55.88 0)
			(effects
				(font
					(size 1.27 1.27)
					(thickness 0.15)
				)
				(justify left bottom)
				(hide yes)
			)
		)
		(property "Description" ""
			(at 189.23 76.2 0)
			(effects
				(font
					(size 1.27 1.27)
				)
			)
		)
		(property "Manufacturer" "Murata"
			(at 209.55 55.88 0)
			(effects
				(font
					(size 1.27 1.27)
					(thickness 0.15)
				)
				(justify left bottom)
				(hide yes)
			)
		)
		(property "MPN" "GRM155R61H104KE14D"
			(at 207.01 55.88 0)
			(effects
				(font
					(size 1.27 1.27)
					(thickness 0.15)
				)
				(justify left bottom)
				(hide yes)
			)
		)
		(property "Val" "100n"
			(at 189.865 75.565 90)
			(effects
				(font
					(size 1.27 1.27)
					(thickness 0.15)
				)
				(justify right)
			)
		)
		(property "License" "Apache-2.0"
			(at 212.09 55.88 0)
			(effects
				(font
					(size 1.27 1.27)
					(thickness 0.15)
				)
				(justify left bottom)
				(hide yes)
			)
		)
		(property "Author" "Antmicro"
			(at 214.63 55.88 0)
			(effects
				(font
					(size 1.27 1.27)
					(thickness 0.15)
				)
				(justify left bottom)
				(hide yes)
			)
		)
		(property "Voltage" "50V"
			(at 217.17 55.88 0)
			(effects
				(font
					(size 1.27 1.27)
				)
				(justify left bottom)
				(hide yes)
			)
		)
		(property "Dielectric" "X5R"
			(at 219.71 55.88 0)
			(effects
				(font
					(size 1.27 1.27)
				)
				(justify left bottom)
				(hide yes)
			)
		)
		(pin "1"
		)
		(pin "2"
		)
		(instances
			(project "k410t-devboard"
				(path ""
					(reference "C16")
					(unit 1)
				)
			)
		)
	)
)
